G04 ================== begin FILE IDENTIFICATION RECORD ==================*
G04 Layout Name:  D:/<user>/Wistron_project/16342-2/gbr/16342-2.brd*
G04 Film Name:    L7GND*
G04 File Format:  Gerber RS274X*
G04 File Origin:  Cadence Allegro 16.5-S056*
G04 Origin Date:  Mon Aug 07 11:24:54 2017*
G04 *
G04 Layer:  VIA CLASS/L7GND*
G04 Layer:  PIN/L7GND*
G04 Layer:  ETCH/L7GND*
G04 Layer:  DRAWING FORMAT/LAYER_PCB_STORY*
G04 Layer:  DRAWING FORMAT/LAYER_L7GND*
G04 *
G04 Offset:    (0.00 0.00)*
G04 Mirror:    No*
G04 Mode:      Negative*
G04 Rotation:  0*
G04 FullContactRelief:  No*
G04 UndefLineWidth:     6.00*
G04 ================== end FILE IDENTIFICATION RECORD ====================*
%FSLAX35Y35*MOIN*%
%IR0*IPPOS*OFA0.00000B0.00000*MIA0B0*SFA1.00000B1.00000*%
%AMMACRO11*
4,1,13,.02632,.01218,
.028035,.007425,
.028899,.002443,
.028884,-.002612,
.027991,-.007588,
.02632,-.01218,
.03005,-.01591,
.032356,-.01045,
.033679,-.004673,
.033979,.001247,
.033246,.007128,
.031504,.012793,
.03005,.01591,
.02632,.01218,
0.0*
4,1,13,.01218,-.02632,
.007425,-.028035,
.002443,-.028899,
-.002612,-.028884,
-.007588,-.027991,
-.01218,-.02632,
-.01591,-.03005,
-.01045,-.032356,
-.004673,-.033679,
.001247,-.033979,
.007128,-.033246,
.012793,-.031504,
.01591,-.03005,
.01218,-.02632,
0.0*
4,1,13,-.02632,-.01218,
-.028035,-.007425,
-.028899,-.002443,
-.028884,.002612,
-.027991,.007588,
-.02632,.01218,
-.03005,.01591,
-.032356,.01045,
-.033679,.004673,
-.033979,-.001247,
-.033246,-.007128,
-.031504,-.012793,
-.03005,-.01591,
-.02632,-.01218,
0.0*
4,1,13,-.01218,.02632,
-.007425,.028035,
-.002443,.028899,
.002612,.028884,
.007588,.027991,
.01218,.02632,
.01591,.03005,
.01045,.032356,
.004673,.033679,
-.001247,.033979,
-.007128,.033246,
-.012793,.031504,
-.01591,.03005,
-.01218,.02632,
0.0*
%
%ADD11MACRO11*%
%ADD29O,.072X.123*%
%ADD13C,.03*%
%ADD26C,.032*%
%ADD24C,.06*%
%ADD33C,.043*%
%ADD32C,.062*%
%ADD40C,.063*%
%ADD37C,.072*%
%ADD22C,.036*%
%ADD39C,.091*%
%ADD23C,.028*%
%ADD28C,.056*%
%ADD31C,.076*%
%ADD10C,.068*%
%AMMACRO42*
4,1,15,.00398,.00044,
.003999,.000208,
.004004,-.000025,
.003996,-.000258,
.00398,-.00044,
.00483,-.00129,
.004897,-.001007,
.004947,-.000721,
.004981,-.000432,
.004997,-.000141,
.004997,.000149,
.00498,.00044,
.004946,.000729,
.004895,.001015,
.00483,.00129,
.00398,.00044,
45.*
4,1,15,.00044,-.00398,
.000208,-.003999,
-.000025,-.004004,
-.000258,-.003996,
-.00044,-.00398,
-.00129,-.00483,
-.001007,-.004897,
-.000721,-.004947,
-.000432,-.004981,
-.000141,-.004997,
.000149,-.004997,
.00044,-.00498,
.000729,-.004946,
.001015,-.004895,
.00129,-.00483,
.00044,-.00398,
45.*
4,1,15,-.00398,-.00044,
-.003999,-.000208,
-.004004,.000025,
-.003996,.000258,
-.00398,.00044,
-.00483,.00129,
-.004897,.001007,
-.004947,.000721,
-.004981,.000432,
-.004997,.000141,
-.004997,-.000149,
-.00498,-.00044,
-.004946,-.000729,
-.004895,-.001015,
-.00483,-.00129,
-.00398,-.00044,
45.*
4,1,15,-.00044,.00398,
-.000208,.003999,
.000025,.004004,
.000258,.003996,
.00044,.00398,
.00129,.00483,
.001007,.004897,
.000721,.004947,
.000432,.004981,
.000141,.004997,
-.000149,.004997,
-.00044,.00498,
-.000729,.004946,
-.001015,.004895,
-.00129,.00483,
-.00044,.00398,
45.*
%
%ADD42MACRO42*%
%AMMACRO18*
4,1,15,.00398,.00044,
.003999,.000208,
.004004,-.000025,
.003996,-.000258,
.00398,-.00044,
.00483,-.00129,
.004897,-.001007,
.004947,-.000721,
.004981,-.000432,
.004997,-.000141,
.004997,.000149,
.00498,.00044,
.004946,.000729,
.004895,.001015,
.00483,.00129,
.00398,.00044,
90.*
4,1,15,.00044,-.00398,
.000208,-.003999,
-.000025,-.004004,
-.000258,-.003996,
-.00044,-.00398,
-.00129,-.00483,
-.001007,-.004897,
-.000721,-.004947,
-.000432,-.004981,
-.000141,-.004997,
.000149,-.004997,
.00044,-.00498,
.000729,-.004946,
.001015,-.004895,
.00129,-.00483,
.00044,-.00398,
90.*
4,1,15,-.00398,-.00044,
-.003999,-.000208,
-.004004,.000025,
-.003996,.000258,
-.00398,.00044,
-.00483,.00129,
-.004897,.001007,
-.004947,.000721,
-.004981,.000432,
-.004997,.000141,
-.004997,-.000149,
-.00498,-.00044,
-.004946,-.000729,
-.004895,-.001015,
-.00483,-.00129,
-.00398,-.00044,
90.*
4,1,15,-.00044,.00398,
-.000208,.003999,
.000025,.004004,
.000258,.003996,
.00044,.00398,
.00129,.00483,
.001007,.004897,
.000721,.004947,
.000432,.004981,
.000141,.004997,
-.000149,.004997,
-.00044,.00498,
-.000729,.004946,
-.001015,.004895,
-.00129,.00483,
-.00044,.00398,
90.*
%
%ADD18MACRO18*%
%AMMACRO12*
4,1,15,.00398,.00044,
.003999,.000208,
.004004,-.000025,
.003996,-.000258,
.00398,-.00044,
.00483,-.00129,
.004897,-.001007,
.004947,-.000721,
.004981,-.000432,
.004997,-.000141,
.004997,.000149,
.00498,.00044,
.004946,.000729,
.004895,.001015,
.00483,.00129,
.00398,.00044,
0.0*
4,1,15,.00044,-.00398,
.000208,-.003999,
-.000025,-.004004,
-.000258,-.003996,
-.00044,-.00398,
-.00129,-.00483,
-.001007,-.004897,
-.000721,-.004947,
-.000432,-.004981,
-.000141,-.004997,
.000149,-.004997,
.00044,-.00498,
.000729,-.004946,
.001015,-.004895,
.00129,-.00483,
.00044,-.00398,
0.0*
4,1,15,-.00398,-.00044,
-.003999,-.000208,
-.004004,.000025,
-.003996,.000258,
-.00398,.00044,
-.00483,.00129,
-.004897,.001007,
-.004947,.000721,
-.004981,.000432,
-.004997,.000141,
-.004997,-.000149,
-.00498,-.00044,
-.004946,-.000729,
-.004895,-.001015,
-.00483,-.00129,
-.00398,-.00044,
0.0*
4,1,15,-.00044,.00398,
-.000208,.003999,
.000025,.004004,
.000258,.003996,
.00044,.00398,
.00129,.00483,
.001007,.004897,
.000721,.004947,
.000432,.004981,
.000141,.004997,
-.000149,.004997,
-.00044,.00498,
-.000729,.004946,
-.001015,.004895,
-.00129,.00483,
-.00044,.00398,
0.0*
%
%ADD12MACRO12*%
%ADD36O,.154X.217*%
%ADD35C,.122*%
%ADD14C,.114*%
%ADD34C,.125*%
%ADD25C,.208*%
%ADD20O,.296X.162*%
%ADD30O,.072X.096*%
%ADD21C,.158*%
%ADD15C,.178*%
%ADD19C,.198*%
%AMMACRO38*
4,1,15,.00398,.00044,
.003999,.000208,
.004004,-.000025,
.003996,-.000258,
.00398,-.00044,
.00483,-.00129,
.004897,-.001007,
.004947,-.000721,
.004981,-.000432,
.004997,-.000141,
.004997,.000149,
.00498,.00044,
.004946,.000729,
.004895,.001015,
.00483,.00129,
.00398,.00044,
225.*
4,1,15,.00044,-.00398,
.000208,-.003999,
-.000025,-.004004,
-.000258,-.003996,
-.00044,-.00398,
-.00129,-.00483,
-.001007,-.004897,
-.000721,-.004947,
-.000432,-.004981,
-.000141,-.004997,
.000149,-.004997,
.00044,-.00498,
.000729,-.004946,
.001015,-.004895,
.00129,-.00483,
.00044,-.00398,
225.*
4,1,15,-.00398,-.00044,
-.003999,-.000208,
-.004004,.000025,
-.003996,.000258,
-.00398,.00044,
-.00483,.00129,
-.004897,.001007,
-.004947,.000721,
-.004981,.000432,
-.004997,.000141,
-.004997,-.000149,
-.00498,-.00044,
-.004946,-.000729,
-.004895,-.001015,
-.00483,-.00129,
-.00398,-.00044,
225.*
4,1,15,-.00044,.00398,
-.000208,.003999,
.000025,.004004,
.000258,.003996,
.00044,.00398,
.00129,.00483,
.001007,.004897,
.000721,.004947,
.000432,.004981,
.000141,.004997,
-.000149,.004997,
-.00044,.00498,
-.000729,.004946,
-.001015,.004895,
-.00129,.00483,
-.00044,.00398,
225.*
%
%ADD38MACRO38*%
%AMMACRO17*
4,1,15,.00398,.00044,
.003999,.000208,
.004004,-.000025,
.003996,-.000258,
.00398,-.00044,
.00483,-.00129,
.004897,-.001007,
.004947,-.000721,
.004981,-.000432,
.004997,-.000141,
.004997,.000149,
.00498,.00044,
.004946,.000729,
.004895,.001015,
.00483,.00129,
.00398,.00044,
180.*
4,1,15,.00044,-.00398,
.000208,-.003999,
-.000025,-.004004,
-.000258,-.003996,
-.00044,-.00398,
-.00129,-.00483,
-.001007,-.004897,
-.000721,-.004947,
-.000432,-.004981,
-.000141,-.004997,
.000149,-.004997,
.00044,-.00498,
.000729,-.004946,
.001015,-.004895,
.00129,-.00483,
.00044,-.00398,
180.*
4,1,15,-.00398,-.00044,
-.003999,-.000208,
-.004004,.000025,
-.003996,.000258,
-.00398,.00044,
-.00483,.00129,
-.004897,.001007,
-.004947,.000721,
-.004981,.000432,
-.004997,.000141,
-.004997,-.000149,
-.00498,-.00044,
-.004946,-.000729,
-.004895,-.001015,
-.00483,-.00129,
-.00398,-.00044,
180.*
4,1,15,-.00044,.00398,
-.000208,.003999,
.000025,.004004,
.000258,.003996,
.00044,.00398,
.00129,.00483,
.001007,.004897,
.000721,.004947,
.000432,.004981,
.000141,.004997,
-.000149,.004997,
-.00044,.00498,
-.000729,.004946,
-.001015,.004895,
-.00129,.00483,
-.00044,.00398,
180.*
%
%ADD17MACRO17*%
%AMMACRO16*
4,1,15,.00398,.00044,
.003999,.000208,
.004004,-.000025,
.003996,-.000258,
.00398,-.00044,
.00483,-.00129,
.004897,-.001007,
.004947,-.000721,
.004981,-.000432,
.004997,-.000141,
.004997,.000149,
.00498,.00044,
.004946,.000729,
.004895,.001015,
.00483,.00129,
.00398,.00044,
270.*
4,1,15,.00044,-.00398,
.000208,-.003999,
-.000025,-.004004,
-.000258,-.003996,
-.00044,-.00398,
-.00129,-.00483,
-.001007,-.004897,
-.000721,-.004947,
-.000432,-.004981,
-.000141,-.004997,
.000149,-.004997,
.00044,-.00498,
.000729,-.004946,
.001015,-.004895,
.00129,-.00483,
.00044,-.00398,
270.*
4,1,15,-.00398,-.00044,
-.003999,-.000208,
-.004004,.000025,
-.003996,.000258,
-.00398,.00044,
-.00483,.00129,
-.004897,.001007,
-.004947,.000721,
-.004981,.000432,
-.004997,.000141,
-.004997,-.000149,
-.00498,-.00044,
-.004946,-.000729,
-.004895,-.001015,
-.00483,-.00129,
-.00398,-.00044,
270.*
4,1,15,-.00044,.00398,
-.000208,.003999,
.000025,.004004,
.000258,.003996,
.00044,.00398,
.00129,.00483,
.001007,.004897,
.000721,.004947,
.000432,.004981,
.000141,.004997,
-.000149,.004997,
-.00044,.00498,
-.000729,.004946,
-.001015,.004895,
-.00129,.00483,
-.00044,.00398,
270.*
%
%ADD16MACRO16*%
%AMMACRO41*
4,1,13,.02442,.01028,
.025834,.005883,
.026463,.001308,
.026288,-.003307,
.025315,-.007822,
.02442,-.01028,
.02819,-.01405,
.030201,-.008941,
.031295,-.003561,
.031438,.001927,
.030626,.007357,
.028883,.012564,
.02819,.01405,
.02442,.01028,
0.0*
4,1,13,.01028,-.02442,
.005883,-.025834,
.001308,-.026463,
-.003307,-.026288,
-.007822,-.025315,
-.01028,-.02442,
-.01405,-.02819,
-.008941,-.030201,
-.003561,-.031295,
.001927,-.031438,
.007357,-.030626,
.012564,-.028883,
.01405,-.02819,
.01028,-.02442,
0.0*
4,1,13,-.02442,-.01028,
-.025834,-.005883,
-.026463,-.001308,
-.026288,.003307,
-.025315,.007822,
-.02442,.01028,
-.02819,.01405,
-.030201,.008941,
-.031295,.003561,
-.031438,-.001927,
-.030626,-.007357,
-.028883,-.012564,
-.02819,-.01405,
-.02442,-.01028,
0.0*
4,1,13,-.01028,.02442,
-.005883,.025834,
-.001308,.026463,
.003307,.026288,
.007822,.025315,
.01028,.02442,
.01405,.02819,
.008941,.030201,
.003561,.031295,
-.001927,.031438,
-.007357,.030626,
-.012564,.028883,
-.01405,.02819,
-.01028,.02442,
0.0*
%
%ADD41MACRO41*%
%AMMACRO27*
4,1,19,.02172,.00757,
.022123,.006294,
.022452,.004997,
.022705,.003683,
.02288,.002357,
.022979,.001023,
.022999,-.000315,
.022942,-.001652,
.022807,-.002983,
.022595,-.004304,
.022307,-.005611,
.021943,-.006898,
.02172,-.00757,
.02556,-.01142,
.027155,-.006808,
.027924,-.001989,
.027846,.00289,
.026921,.007681,
.02556,.01142,
.02172,.00757,
0.0*
4,1,19,.00757,-.02172,
.006294,-.022123,
.004997,-.022452,
.003683,-.022705,
.002357,-.02288,
.001023,-.022979,
-.000315,-.022999,
-.001652,-.022942,
-.002983,-.022807,
-.004304,-.022595,
-.005611,-.022307,
-.006898,-.021943,
-.00757,-.02172,
-.01142,-.02556,
-.006808,-.027155,
-.001989,-.027924,
.00289,-.027846,
.007681,-.026921,
.01142,-.02556,
.00757,-.02172,
0.0*
4,1,19,-.02172,-.00757,
-.022123,-.006294,
-.022452,-.004997,
-.022705,-.003683,
-.02288,-.002357,
-.022979,-.001023,
-.022999,.000315,
-.022942,.001652,
-.022807,.002983,
-.022595,.004304,
-.022307,.005611,
-.021943,.006898,
-.02172,.00757,
-.02556,.01142,
-.027155,.006808,
-.027924,.001989,
-.027846,-.00289,
-.026921,-.007681,
-.02556,-.01142,
-.02172,-.00757,
0.0*
4,1,19,-.00757,.02172,
-.006294,.022123,
-.004997,.022452,
-.003683,.022705,
-.002357,.02288,
-.001023,.022979,
.000315,.022999,
.001652,.022942,
.002983,.022807,
.004304,.022595,
.005611,.022307,
.006898,.021943,
.00757,.02172,
.01142,.02556,
.006808,.027155,
.001989,.027924,
-.00289,.027846,
-.007681,.026921,
-.01142,.02556,
-.00757,.02172,
0.0*
%
%ADD27MACRO27*%
%ADD43C,.02*%
%ADD44C,.006*%
%ADD54C,.07204*%
%ADD53C,.05604*%
%ADD55C,.05804*%
%ADD58C,.06804*%
%ADD59C,.08704*%
%ADD46O,.15002X.21302*%
%ADD45O,.15004X.21304*%
%ADD50C,.11004*%
%ADD56C,.12104*%
%ADD57C,.11804*%
%ADD51C,.15404*%
%ADD47O,.29202X.15802*%
%ADD48O,.29204X.15804*%
%ADD49C,.37406*%
%ADD52C,.29604*%
G75*
%LPD*%
G75*
G36*
G01X-6000Y-6000D02*
X931197D01*
Y769780D01*
X-6000D01*
Y-6000D01*
G37*
%LPC*%
G75*
G36*
G01X903913Y760260D02*
X922094Y723897D01*
G02X922193Y723480I-834J-418D01*
G01Y3937D01*
G02X921260Y3004I-933J0D01*
G01X291457D01*
G02X290524Y3937I0J933D01*
G01Y429331D01*
G03X283583Y436272I-6941J0D01*
G01X124134D01*
G03X117193Y429331I0J-6941D01*
G01Y3937D01*
G02X116260Y3004I-933J0D01*
G01X3937D01*
G02X3004Y3937I0J933D01*
G01Y723480D01*
G02X3103Y723897I933J-1D01*
G01X21284Y760260D01*
G02X22118Y760776I835J-417D01*
G01X386150D01*
G02X386984Y760260I-1J-933D01*
G01X405165Y723897D01*
G02X405264Y723480I-834J-418D01*
G01Y188976D01*
G03X414199Y185972I4973J0D01*
G01X562179D01*
G03X571114Y188976I3962J3004D01*
G01Y297095D01*
G02X571855Y297305I400J1D01*
G03Y316869I15940J9782D01*
G02X571114Y317079I-341J209D01*
G01Y589621D01*
G02X571213Y590038I933J-1D01*
G01X589394Y626401D01*
G02X590228Y626917I835J-417D01*
G01X842520D01*
G03X849461Y633858I0J6941D01*
G01Y759843D01*
G02X850394Y760776I933J0D01*
G01X903079D01*
G02X903913Y760260I-1J-933D01*
G37*
%LPD*%
G75*
G36*
G01X329692Y372018D02*
G02X326672I-1510J0D01*
G01Y375519D01*
G02X329692Y375518I1510J-1D01*
G01Y372018D01*
G37*
G36*
G01X305777Y365792D02*
G02X302757I-1510J0D01*
G01Y369293D01*
G02X305777Y369292I1510J-1D01*
G01Y365792D01*
G37*
G36*
G01X336092Y359474D02*
G02X333072I-1510J0D01*
G01Y362975D01*
G02X336092Y362974I1510J-1D01*
G01Y359474D01*
G37*
G36*
G01X309077Y353192D02*
G02X306057I-1510J0D01*
G01Y356693D01*
G02X309077Y356692I1510J-1D01*
G01Y353192D01*
G37*
G36*
G01X329697Y346816D02*
G02X326677I-1510J0D01*
G01Y350317D01*
G02X329697Y350316I1510J-1D01*
G01Y346816D01*
G37*
G36*
G01X305777Y340592D02*
G02X302757I-1510J0D01*
G01Y344093D01*
G02X305777Y344092I1510J-1D01*
G01Y340592D01*
G37*
G36*
G01X336092Y334221D02*
G02X333072I-1510J0D01*
G01Y337722D01*
G02X336092Y337721I1510J-1D01*
G01Y334221D01*
G37*
G36*
G01X309077Y327992D02*
G02X306057I-1510J0D01*
G01Y331493D01*
G02X309077Y331492I1510J-1D01*
G01Y327992D01*
G37*
G36*
G01X329692Y321624D02*
G02X326672I-1510J0D01*
G01Y325125D01*
G02X329692Y325124I1510J-1D01*
G01Y321624D01*
G37*
G36*
G01X305777Y315392D02*
G02X302757I-1510J0D01*
G01Y318893D01*
G02X305777Y318892I1510J-1D01*
G01Y315392D01*
G37*
G36*
G01X336103Y309084D02*
G02X333083I-1510J0D01*
G01Y312585D01*
G02X336103Y312584I1510J-1D01*
G01Y309084D01*
G37*
G36*
G01X309077Y302792D02*
G02X306057I-1510J0D01*
G01Y306293D01*
G02X309077Y306292I1510J-1D01*
G01Y302792D01*
G37*
G36*
G01X329692Y296477D02*
G02X326672I-1510J0D01*
G01Y299978D01*
G02X329692Y299977I1510J-1D01*
G01Y296477D01*
G37*
G36*
G01X305777Y290192D02*
G02X302757I-1510J0D01*
G01Y293693D01*
G02X305777Y293692I1510J-1D01*
G01Y290192D01*
G37*
G36*
G01X335617Y283854D02*
G02X332597I-1510J0D01*
G01Y287355D01*
G02X335617Y287354I1510J-1D01*
G01Y283854D01*
G37*
G36*
G01X309077Y277592D02*
G02X306057I-1510J0D01*
G01Y281093D01*
G02X309077Y281092I1510J-1D01*
G01Y277592D01*
G37*
G36*
G01X306058Y265008D02*
G02X303038I-1510J0D01*
G01Y268509D01*
G02X306058Y268508I1510J-1D01*
G01Y265008D01*
G37*
G36*
G01X805747Y555869D02*
X805750Y555872D01*
X808119Y558240D01*
X808122Y558244D01*
G02X810250Y556128I1115J-1007D01*
G01X807872Y553750D01*
G02X805747Y555869I-1109J1013D01*
G37*
G36*
G01X787247D02*
X787250Y555872D01*
X789619Y558240D01*
X789622Y558244D01*
G02X791750Y556128I1115J-1007D01*
G01X789372Y553750D01*
G02X787247Y555869I-1109J1013D01*
G37*
G36*
G01X796747Y555369D02*
X796750Y555372D01*
X799119Y557740D01*
X799122Y557744D01*
G02X801250Y555628I1115J-1007D01*
G01X798872Y553250D01*
G02X796747Y555369I-1109J1013D01*
G37*
G36*
G01X777747Y554869D02*
X777750Y554872D01*
X780119Y557240D01*
X780122Y557244D01*
G02X782250Y555128I1115J-1007D01*
G01X779872Y552750D01*
G02X777747Y554869I-1109J1013D01*
G37*
G36*
G01X824247Y554369D02*
X824250Y554372D01*
X826619Y556740D01*
X826622Y556744D01*
G02X828750Y554628I1115J-1007D01*
G01X826372Y552250D01*
G02X824247Y554369I-1109J1013D01*
G37*
G36*
G01X767247Y553869D02*
X767250Y553872D01*
X769619Y556240D01*
X769622Y556244D01*
G02X771750Y554128I1115J-1007D01*
G01X769372Y551750D01*
G02X767247Y553869I-1109J1013D01*
G37*
G36*
G01X689685Y553463D02*
X687307Y551085D01*
G02X685182Y553204I-1109J1013D01*
G01X685185Y553207D01*
X687554Y555575D01*
X687557Y555579D01*
G02X689685Y553463I1115J-1007D01*
G37*
G36*
G01X707666Y552952D02*
X707669Y552955D01*
X710038Y555323D01*
X710041Y555327D01*
G02X712169Y553211I1115J-1007D01*
G01X709791Y550833D01*
G02X707666Y552952I-1109J1013D01*
G37*
G36*
G01X698437Y552184D02*
X698440Y552187D01*
X700809Y554555D01*
X700812Y554559D01*
G02X702940Y552443I1115J-1007D01*
G01X700562Y550065D01*
G02X698437Y552184I-1109J1013D01*
G37*
G36*
G01X727666Y551052D02*
X727669Y551055D01*
X730038Y553423D01*
X730041Y553427D01*
G02X732169Y551311I1115J-1007D01*
G01X729791Y548933D01*
G02X727666Y551052I-1109J1013D01*
G37*
G36*
G01X716813Y550962D02*
X716816Y550965D01*
X719185Y553333D01*
X719188Y553337D01*
G02X721316Y551221I1115J-1007D01*
G01X718938Y548843D01*
G02X716813Y550962I-1109J1013D01*
G37*
G36*
G01X811747Y549369D02*
X811750Y549372D01*
X814119Y551740D01*
X814122Y551744D01*
G02X816250Y549628I1115J-1007D01*
G01X813872Y547250D01*
G02X811747Y549369I-1109J1013D01*
G37*
G36*
G01X755247D02*
X755250Y549372D01*
X757619Y551740D01*
X757622Y551744D01*
G02X759750Y549628I1115J-1007D01*
G01X757372Y547250D01*
G02X755247Y549369I-1109J1013D01*
G37*
G36*
G01X838879Y547866D02*
X838882Y547869D01*
X841251Y550237D01*
X841254Y550241D01*
G02X843382Y548125I1115J-1007D01*
G01X841004Y545747D01*
G02X838879Y547866I-1109J1013D01*
G37*
G36*
G01X674511Y545936D02*
X672133Y543558D01*
G02X670008Y545677I-1109J1013D01*
G01X670011Y545680D01*
X672380Y548048D01*
X672383Y548052D01*
G02X674511Y545936I1115J-1007D01*
G37*
G36*
G01X683802Y544118D02*
X683805Y544121D01*
X686174Y546489D01*
X686177Y546493D01*
G02X688305Y544377I1115J-1007D01*
G01X685927Y541999D01*
G02X683802Y544118I-1109J1013D01*
G37*
G36*
G01X661408Y540365D02*
X659030Y537987D01*
G02X656905Y540106I-1109J1013D01*
G01X656908Y540109D01*
X659277Y542477D01*
X659280Y542481D01*
G02X661408Y540365I1115J-1007D01*
G37*
G36*
G01X723958Y522019D02*
X720609D01*
G02Y525019I-73J1500D01*
G01X723963D01*
G02Y522019I73J-1500D01*
G01X723958D01*
G37*
G36*
G01X558210Y173420D02*
Y169100D01*
X558219Y169072D01*
G02X554379I-1920J-568D01*
G01X554388Y169100D01*
Y173420D01*
X554379Y173448D01*
G02X558219I1920J568D01*
G01X558210Y173420D01*
G37*
G36*
G01X529864D02*
Y169100D01*
X529873Y169072D01*
G02X526033I-1920J-568D01*
G01X526042Y169100D01*
Y173420D01*
X526033Y173448D01*
G02X529873I1920J568D01*
G01X529864Y173420D01*
G37*
G36*
G01X473172D02*
Y169100D01*
X473180Y169072D01*
G02X469340I-1920J-568D01*
G01X469348Y169100D01*
Y173420D01*
X469340Y173448D01*
G02X473180I1920J568D01*
G01X473172Y173420D01*
G37*
G36*
G01X551124Y149798D02*
Y145478D01*
X551132Y145450D01*
G02X547292I-1920J-568D01*
G01X547300Y145478D01*
Y149798D01*
X547292Y149826D01*
G02X551132I1920J568D01*
G01X551124Y149798D01*
G37*
G36*
G01X536950D02*
Y145478D01*
X536959Y145450D01*
G02X533119I-1920J-568D01*
G01X533128Y145478D01*
Y149798D01*
X533119Y149826D01*
G02X536959I1920J568D01*
G01X536950Y149798D01*
G37*
G36*
G01X522778D02*
Y145478D01*
X522786Y145450D01*
G02X518946I-1920J-568D01*
G01X518954Y145478D01*
Y149798D01*
X518946Y149826D01*
G02X522786I1920J568D01*
G01X522778Y149798D01*
G37*
G36*
G01X508604D02*
Y145478D01*
X508613Y145450D01*
G02X504773I-1920J-568D01*
G01X504782Y145478D01*
Y149798D01*
X504773Y149826D01*
G02X508613I1920J568D01*
G01X508604Y149798D01*
G37*
G36*
G01X466084D02*
Y145478D01*
X466093Y145450D01*
G02X462253I-1920J-568D01*
G01X462262Y145478D01*
Y149798D01*
X462253Y149826D01*
G02X466093I1920J568D01*
G01X466084Y149798D01*
G37*
G36*
G01X451912D02*
Y145478D01*
X451920Y145450D01*
G02X448080I-1920J-568D01*
G01X448088Y145478D01*
Y149798D01*
X448080Y149826D01*
G02X451920I1920J568D01*
G01X451912Y149798D01*
G37*
G36*
G01X437738D02*
Y145478D01*
X437747Y145450D01*
G02X433907I-1920J-568D01*
G01X433916Y145478D01*
Y149798D01*
X433907Y149826D01*
G02X437747I1920J568D01*
G01X437738Y149798D01*
G37*
G36*
G01X423564D02*
Y145478D01*
X423573Y145450D01*
G02X419733I-1920J-568D01*
G01X419742Y145478D01*
Y149798D01*
X419733Y149826D01*
G02X423573I1920J568D01*
G01X423564Y149798D01*
G37*
G36*
G01X558210Y145074D02*
Y140754D01*
X558219Y140726D01*
G02X554379I-1920J-568D01*
G01X554388Y140754D01*
Y145074D01*
X554379Y145102D01*
G02X558219I1920J568D01*
G01X558210Y145074D01*
G37*
G36*
G01X544038D02*
Y140754D01*
X544046Y140726D01*
G02X540206I-1920J-568D01*
G01X540214Y140754D01*
Y145074D01*
X540206Y145102D01*
G02X544046I1920J568D01*
G01X544038Y145074D01*
G37*
G36*
G01X529864D02*
Y140754D01*
X529873Y140726D01*
G02X526033I-1920J-568D01*
G01X526042Y140754D01*
Y145074D01*
X526033Y145102D01*
G02X529873I1920J568D01*
G01X529864Y145074D01*
G37*
G36*
G01X515690D02*
Y140754D01*
X515699Y140726D01*
G02X511859I-1920J-568D01*
G01X511868Y140754D01*
Y145074D01*
X511859Y145102D01*
G02X515699I1920J568D01*
G01X515690Y145074D01*
G37*
G36*
G01X473172D02*
Y140754D01*
X473180Y140726D01*
G02X469340I-1920J-568D01*
G01X469348Y140754D01*
Y145074D01*
X469340Y145102D01*
G02X473180I1920J568D01*
G01X473172Y145074D01*
G37*
G36*
G01X458998D02*
Y140754D01*
X459006Y140726D01*
G02X455166I-1920J-568D01*
G01X455174Y140754D01*
Y145074D01*
X455166Y145102D01*
G02X459006I1920J568D01*
G01X458998Y145074D01*
G37*
G36*
G01X444824D02*
Y140754D01*
X444833Y140726D01*
G02X440993I-1920J-568D01*
G01X441002Y140754D01*
Y145074D01*
X440993Y145102D01*
G02X444833I1920J568D01*
G01X444824Y145074D01*
G37*
G36*
G01X430652D02*
Y140754D01*
X430660Y140726D01*
G02X426820I-1920J-568D01*
G01X426828Y140754D01*
Y145074D01*
X426820Y145102D01*
G02X430660I1920J568D01*
G01X430652Y145074D01*
G37*
G36*
G01X551124Y135625D02*
Y131305D01*
X551132Y131277D01*
G02X547292I-1920J-568D01*
G01X547300Y131305D01*
Y135625D01*
X547292Y135653D01*
G02X551132I1920J568D01*
G01X551124Y135625D01*
G37*
G36*
G01X536950D02*
Y131305D01*
X536959Y131277D01*
G02X533119I-1920J-568D01*
G01X533128Y131305D01*
Y135625D01*
X533119Y135653D01*
G02X536959I1920J568D01*
G01X536950Y135625D01*
G37*
G36*
G01X522778D02*
Y131305D01*
X522786Y131277D01*
G02X518946I-1920J-568D01*
G01X518954Y131305D01*
Y135625D01*
X518946Y135653D01*
G02X522786I1920J568D01*
G01X522778Y135625D01*
G37*
G36*
G01X508604D02*
Y131305D01*
X508613Y131277D01*
G02X504773I-1920J-568D01*
G01X504782Y131305D01*
Y135625D01*
X504773Y135653D01*
G02X508613I1920J568D01*
G01X508604Y135625D01*
G37*
G36*
G01X466084D02*
Y131305D01*
X466093Y131277D01*
G02X462253I-1920J-568D01*
G01X462262Y131305D01*
Y135625D01*
X462253Y135653D01*
G02X466093I1920J568D01*
G01X466084Y135625D01*
G37*
G36*
G01X451912D02*
Y131305D01*
X451920Y131277D01*
G02X448080I-1920J-568D01*
G01X448088Y131305D01*
Y135625D01*
X448080Y135653D01*
G02X451920I1920J568D01*
G01X451912Y135625D01*
G37*
G36*
G01X437738D02*
Y131305D01*
X437747Y131277D01*
G02X433907I-1920J-568D01*
G01X433916Y131305D01*
Y135625D01*
X433907Y135653D01*
G02X437747I1920J568D01*
G01X437738Y135625D01*
G37*
G36*
G01X423564D02*
Y131305D01*
X423573Y131277D01*
G02X419733I-1920J-568D01*
G01X419742Y131305D01*
Y135625D01*
X419733Y135653D01*
G02X423573I1920J568D01*
G01X423564Y135625D01*
G37*
G36*
G01X558210Y130900D02*
Y126581D01*
X558219Y126553D01*
G02X554379I-1920J-568D01*
G01X554388Y126581D01*
Y130900D01*
X554379Y130928D01*
G02X558219I1920J568D01*
G01X558210Y130900D01*
G37*
G36*
G01X544038D02*
Y126581D01*
X544046Y126553D01*
G02X540206I-1920J-568D01*
G01X540214Y126581D01*
Y130900D01*
X540206Y130928D01*
G02X544046I1920J568D01*
G01X544038Y130900D01*
G37*
G36*
G01X529864D02*
Y126581D01*
X529873Y126553D01*
G02X526033I-1920J-568D01*
G01X526042Y126581D01*
Y130900D01*
X526033Y130928D01*
G02X529873I1920J568D01*
G01X529864Y130900D01*
G37*
G36*
G01X515690D02*
Y126581D01*
X515699Y126553D01*
G02X511859I-1920J-568D01*
G01X511868Y126581D01*
Y130900D01*
X511859Y130928D01*
G02X515699I1920J568D01*
G01X515690Y130900D01*
G37*
G36*
G01X473172D02*
Y126581D01*
X473180Y126553D01*
G02X469340I-1920J-568D01*
G01X469348Y126581D01*
Y130900D01*
X469340Y130928D01*
G02X473180I1920J568D01*
G01X473172Y130900D01*
G37*
G36*
G01X458998D02*
Y126581D01*
X459006Y126553D01*
G02X455166I-1920J-568D01*
G01X455174Y126581D01*
Y130900D01*
X455166Y130928D01*
G02X459006I1920J568D01*
G01X458998Y130900D01*
G37*
G36*
G01X444824D02*
Y126581D01*
X444833Y126553D01*
G02X440993I-1920J-568D01*
G01X441002Y126581D01*
Y130900D01*
X440993Y130928D01*
G02X444833I1920J568D01*
G01X444824Y130900D01*
G37*
G36*
G01X430652D02*
Y126581D01*
X430660Y126553D01*
G02X426820I-1920J-568D01*
G01X426828Y126581D01*
Y130900D01*
X426820Y130928D01*
G02X430660I1920J568D01*
G01X430652Y130900D01*
G37*
G36*
G01X509942Y101692D02*
X505815D01*
G02Y104696I-36J1502D01*
G01X509945D01*
G02Y101692I36J-1502D01*
G01X509942D01*
G37*
G54D54*
X305906Y182874D03*
G54D53*
X201801Y684252D03*
X225601D03*
G54D55*
X305906Y388386D03*
G54D58*
X666929Y510236D03*
X765354D03*
G54D59*
X745669D03*
X844094D03*
G54D46*
X706299Y201771D03*
Y83661D03*
G54D45*
X804724Y201772D03*
Y83661D03*
G54D50*
X34652Y111485D03*
X33297Y703990D03*
X899219Y47960D03*
G54D56*
X488838Y137225D03*
G54D57*
Y164744D03*
G54D51*
X90157Y413582D03*
X309055Y157677D03*
G54D47*
X309252Y413583D03*
G54D48*
X89764Y238386D03*
G54D49*
X70866Y98425D03*
Y472441D03*
X49212Y740157D03*
X314961Y472441D03*
X364173Y740157D03*
X405512Y39370D03*
X590551Y472441D03*
X612205Y606299D03*
X875984Y31496D03*
Y472441D03*
Y606299D03*
Y740157D03*
G54D52*
X163189Y669291D03*
G54D11*
X56102Y24606D03*
X103346Y34449D03*
G54D29*
X339331Y49803D03*
X360669Y91929D03*
G54D13*
X38500Y56500D03*
X46500Y48500D03*
X28123Y453658D03*
X62276Y550493D03*
X67852Y539219D03*
X67853Y564416D03*
Y554967D03*
Y542368D03*
X64701Y561266D03*
X63456Y555041D03*
X67853Y561266D03*
X64701Y542366D03*
X64151Y521695D03*
X53524Y521269D03*
Y526995D03*
Y532622D03*
X52613Y538242D03*
X52408Y543876D03*
X52603Y549526D03*
X52485Y555153D03*
X53300Y560879D03*
X67853Y577015D03*
X64703Y586463D03*
X64701Y567566D03*
X67853Y570715D03*
X53302Y567317D03*
X58926Y582407D03*
X28667Y634097D03*
X42550Y599224D03*
X56100Y676000D03*
X86268Y58755D03*
X78268Y66755D03*
X121233Y450900D03*
X108500Y475500D03*
X97074Y492891D03*
X112722Y493971D03*
X98400Y473200D03*
X140490Y488605D03*
X132777Y462639D03*
X130787Y479138D03*
X113300Y448564D03*
X118065Y448535D03*
X100600Y490750D03*
X138023Y456188D03*
X140985Y454250D03*
X135262Y475726D03*
X74151Y545516D03*
X86750Y542368D03*
X126337Y554085D03*
X74498Y551757D03*
X130311Y546700D03*
X71002Y539219D03*
X81276Y548766D03*
X119605Y548705D03*
X86750Y539218D03*
X74076Y535966D03*
X83600Y545518D03*
X75508Y542198D03*
X89899Y545518D03*
X127300Y543200D03*
X71002Y542368D03*
X117200Y546300D03*
X89899Y539218D03*
X83600Y539219D03*
X71002Y545518D03*
X86750D03*
X122600Y557480D03*
X71002Y558117D03*
X86750Y554965D03*
Y558115D03*
X83600Y551817D03*
X71002Y564396D03*
Y561266D03*
X83600Y564415D03*
X86750D03*
X75066Y563235D03*
X83600Y561265D03*
X71002Y554967D03*
X86750Y551815D03*
X123300Y530300D03*
X119400Y521700D03*
X133800Y528500D03*
X102601Y507300D03*
X123200Y534600D03*
X78276Y545566D03*
X93744Y542019D03*
X133554Y537374D03*
X71002Y548668D03*
X92600Y535623D03*
X86750Y561265D03*
X89899D03*
X94720Y557158D03*
X92286Y521695D03*
X86659D03*
X81032D03*
X75405D03*
X69778D03*
X97913D03*
X96371Y534124D03*
X125400Y498600D03*
X130607Y569636D03*
X126347Y569556D03*
X117400Y567650D03*
X83600Y573865D03*
X74152Y567565D03*
X86750Y586463D03*
X71002Y567565D03*
X86750Y583313D03*
X74152Y580163D03*
X83601Y580164D03*
X89899Y577014D03*
X74152Y577013D03*
X86750Y577014D03*
X96570Y581730D03*
X118900Y609900D03*
X116400Y626600D03*
X124903Y613900D03*
X124793Y617299D03*
X139500Y611200D03*
X138970Y632277D03*
X74152Y583312D03*
X94011Y597066D03*
X101608Y596523D03*
X93048Y580164D03*
X89899Y567565D03*
X93049Y573864D03*
X93051Y587466D03*
X83600Y567565D03*
X128700Y615500D03*
X138700Y636655D03*
X103098Y620264D03*
X98537Y601094D03*
X102509Y601100D03*
X103109Y608572D03*
X103124Y605153D03*
X103098Y612064D03*
Y624364D03*
X113672Y605134D03*
X113512Y613401D03*
X113426Y609234D03*
X108137Y615870D03*
X113400Y621400D03*
Y617400D03*
X70700Y629000D03*
X133835Y609620D03*
X86028Y696439D03*
X81928Y697539D03*
X106879Y707245D03*
X125376Y701124D03*
X106635Y701465D03*
X94106Y699683D03*
X131300Y650100D03*
X135000Y650000D03*
X89868Y689124D03*
X121300Y651900D03*
X139774Y666686D03*
X119849Y709715D03*
X106355Y710745D03*
X143700Y469000D03*
X188708Y468154D03*
X175115Y463761D03*
X167821Y488301D03*
X208370Y491570D03*
X200260Y465900D03*
X211324Y489886D03*
X167656Y465300D03*
X189700Y463500D03*
X181200Y489451D03*
X155710Y485200D03*
X172300Y478400D03*
X172900Y484101D03*
X169252Y483871D03*
X213159Y460326D03*
X154334Y465100D03*
X149000Y488600D03*
X171537Y464400D03*
X179100Y455800D03*
X201600Y486500D03*
X198200D03*
X190036Y485520D03*
X194411Y485447D03*
X163031Y441700D03*
X193400Y463300D03*
X153489Y481559D03*
X148490Y451286D03*
X144245Y452344D03*
X151877Y450439D03*
X155877D03*
X145000Y488600D03*
X167680Y510640D03*
X166761Y498900D03*
X187500Y523700D03*
X154730Y512704D03*
X158241Y512675D03*
X170700Y513600D03*
X182870Y513832D03*
X212300Y529000D03*
X141980Y508590D03*
X146900Y512500D03*
X185615Y498015D03*
X174900Y499800D03*
X203610Y529397D03*
X179400Y525100D03*
X182964Y510414D03*
X154400Y533500D03*
X187100Y509600D03*
X195200Y513200D03*
X162537Y499000D03*
X160286Y508429D03*
X183750Y524200D03*
X143415Y530143D03*
X171200Y509840D03*
X170800Y499800D03*
X166600Y524100D03*
X144087Y526413D03*
X176900Y496500D03*
X174717Y524010D03*
X178869Y509793D03*
X200650Y497862D03*
X199501Y509275D03*
X191200Y522500D03*
X191300Y525900D03*
X174700Y509600D03*
X207500Y505812D03*
X158000Y499000D03*
X200200Y529200D03*
X156000Y496100D03*
X203696Y533000D03*
X156200Y535800D03*
X188834Y496920D03*
X190929Y512592D03*
X150553Y512500D03*
X148050Y523740D03*
X196800Y497862D03*
X193200Y497000D03*
X174400Y519283D03*
X148409Y575672D03*
X144876Y590854D03*
X148409Y579353D03*
X144876Y587173D03*
X185100Y614300D03*
X179700Y615300D03*
X151800Y615400D03*
X197611Y630698D03*
X193400Y630600D03*
X174799Y630303D03*
X171400Y630200D03*
X199950Y614000D03*
X196100Y614050D03*
X203900Y614100D03*
X144737Y630882D03*
X200100Y633300D03*
X209193Y614249D03*
X162750Y612217D03*
X164400Y609200D03*
X182100Y629800D03*
X178200D03*
X148210Y629830D03*
X141742Y624666D03*
X144263Y609023D03*
X151800Y610300D03*
X188899Y629597D03*
X185500Y629700D03*
X154500Y629600D03*
X195600Y646000D03*
X205827Y695000D03*
X188600Y696800D03*
X159058Y641132D03*
X142572Y640332D03*
X150872D03*
X177100Y640400D03*
X173000D03*
X193400Y639700D03*
X189500D03*
X185300D03*
X181000D03*
X198700D03*
X151949Y691715D03*
X176447Y704925D03*
X162700Y703500D03*
X150849Y710215D03*
X162360Y706888D03*
X168273Y696434D03*
X158994Y694545D03*
X205800Y698400D03*
X210123Y662100D03*
X200000Y664200D03*
X204100Y646500D03*
X199600Y646300D03*
X195500Y696900D03*
X207000Y654400D03*
X185598Y709274D03*
X182200Y709400D03*
X143174Y666586D03*
X162100Y711215D03*
X275276Y494017D03*
X275700Y490300D03*
X275100Y472400D03*
X264800Y467400D03*
X278800Y467500D03*
X277455Y446150D03*
X226475Y480400D03*
X254100Y440800D03*
X257950Y440600D03*
X226500Y477000D03*
X275113Y476513D03*
X266664Y493000D03*
X214808Y463300D03*
X231400Y489800D03*
X237903D03*
X267670Y485870D03*
X271100Y485900D03*
X222995Y443805D03*
X240900Y440900D03*
X236400Y440800D03*
X280600Y448900D03*
X214900Y490000D03*
X231476Y449662D03*
X276591Y483709D03*
X245874Y458478D03*
X242500Y458900D03*
X253400Y453500D03*
X273400Y449700D03*
X249465Y458000D03*
X252626Y469150D03*
X244400Y478600D03*
X244300Y474150D03*
X225532Y450047D03*
X237600Y455500D03*
X233664Y482859D03*
X226607Y444058D03*
X230610Y444055D03*
X272100Y537500D03*
X251346Y554100D03*
X256816Y563982D03*
X262996Y548757D03*
X231450Y563000D03*
X270021Y549394D03*
X283600Y539294D03*
X242700Y548600D03*
X252400Y539600D03*
X271715Y556690D03*
X263400Y531500D03*
X233850Y552201D03*
X234943Y565199D03*
X260513Y564135D03*
X265100Y562300D03*
X227600Y563000D03*
X254494Y529198D03*
X248459Y523892D03*
X269100Y509063D03*
X244850Y540150D03*
X248700Y540000D03*
X228200Y496200D03*
X263600Y540700D03*
X226357Y504514D03*
X257894Y529254D03*
X263600Y535350D03*
X223800Y531600D03*
X236400Y502150D03*
X246508Y532821D03*
X228100Y545500D03*
X227100Y525400D03*
X228800Y542100D03*
X238600Y509900D03*
X228313Y552169D03*
X233100Y509800D03*
X275100D03*
X260900Y553900D03*
X242600Y509800D03*
X233607Y557671D03*
X241154Y536017D03*
X250445Y548551D03*
X255800Y539600D03*
X279200Y531600D03*
X250400Y636976D03*
X215800Y631200D03*
X260705Y598359D03*
X232896Y613795D03*
X231200Y576800D03*
X234700Y581600D03*
X254408Y586483D03*
X255400Y579500D03*
X225900Y630988D03*
X230063Y618667D03*
X274100Y591000D03*
X279745Y608000D03*
X255663Y617763D03*
X276376Y574132D03*
X281636Y588796D03*
X231000Y571900D03*
X242333Y593800D03*
X257346Y599169D03*
X257332Y602569D03*
X258398Y605915D03*
Y609484D03*
X218200Y609500D03*
X262694Y568076D03*
X261300Y571300D03*
X235800Y615100D03*
X233447Y603747D03*
X232300Y600300D03*
X258596Y586356D03*
X259848Y583194D03*
X279214Y591383D03*
X275652Y577455D03*
X237100Y590000D03*
X234087Y618038D03*
X248800Y582000D03*
X273022Y580751D03*
X268200Y578700D03*
X259000Y617000D03*
X234800Y572000D03*
X256007Y575050D03*
X281975Y572963D03*
X279800Y569182D03*
X264200Y574100D03*
X261810Y633980D03*
X264800Y632300D03*
X276783Y588907D03*
X258873Y631373D03*
X215400Y626800D03*
X281510Y583003D03*
X276400Y700650D03*
X254900Y701950D03*
X223013Y645672D03*
X231500Y659100D03*
X255050Y675750D03*
X271240Y698960D03*
X243731Y709100D03*
X272900Y669100D03*
X254600Y685100D03*
X278150Y648363D03*
X284000Y678300D03*
X263800Y648902D03*
X236000Y646100D03*
X272300Y665700D03*
X266398Y679250D03*
X226708Y645869D03*
X239400Y677600D03*
X267045Y695881D03*
X215606Y645300D03*
X277600Y680200D03*
X217638Y695562D03*
X239000Y691000D03*
X276400Y697250D03*
X254700Y708900D03*
X271220Y679910D03*
X255000Y679900D03*
X235042Y656173D03*
X263500Y643212D03*
X243100Y677500D03*
X267100Y699700D03*
X266400Y662200D03*
X254648Y745463D03*
X268520Y719420D03*
X258431Y712169D03*
X268230Y723570D03*
X352000Y109000D03*
X355500D03*
X305651Y199283D03*
X294720Y182200D03*
X320700Y177800D03*
X294720Y178600D03*
Y185600D03*
X307567Y277592D03*
X304548Y268508D03*
Y265008D03*
X335100Y228117D03*
X333882Y273978D03*
Y270578D03*
X335098Y233078D03*
X305782Y230874D03*
X334482Y263778D03*
X333782Y267178D03*
X324000Y222800D03*
X305782Y220674D03*
X305682Y224074D03*
X305782Y217274D03*
X334198Y248824D03*
X305454Y244461D03*
X334282Y252378D03*
X305373Y251101D03*
X306412Y254339D03*
X334260Y255820D03*
X305882Y234274D03*
X305772Y237673D03*
X305781Y241076D03*
X334107Y287354D03*
Y283854D03*
X304267Y344092D03*
Y340592D03*
X307567Y331492D03*
Y327992D03*
X304267Y318892D03*
Y315392D03*
X307567Y306292D03*
Y302792D03*
X304267Y293692D03*
Y290192D03*
X334582Y337721D03*
Y334221D03*
X328187Y350316D03*
Y346816D03*
X328182Y325124D03*
Y321624D03*
X334593Y312584D03*
Y309084D03*
X328182Y299977D03*
Y296477D03*
X307567Y281092D03*
X304267Y369292D03*
Y365792D03*
X307567Y356692D03*
Y353192D03*
X328182Y375518D03*
Y372018D03*
X334582Y362974D03*
Y359474D03*
X336000Y384400D03*
X336230Y377800D03*
X350408Y393708D03*
X348006Y391300D03*
X321859Y388315D03*
X321100Y384874D03*
X346300Y374600D03*
X349100Y379100D03*
X303900Y380574D03*
X348997Y491678D03*
X295700Y428400D03*
X293326Y494174D03*
X344900Y442800D03*
X344688Y493896D03*
X343050Y438900D03*
X339900Y454000D03*
X328313Y435513D03*
X324916Y435360D03*
X321700Y436650D03*
X296254Y546706D03*
X285833Y557629D03*
X302700Y551300D03*
X339062Y521100D03*
X344600Y507600D03*
X341300Y536200D03*
X352921Y536521D03*
X311900Y514900D03*
X287500Y518000D03*
X297850Y524500D03*
X293600Y518400D03*
X288000Y561000D03*
X313300Y518800D03*
X354300Y500245D03*
X288311Y496200D03*
X355600Y506600D03*
X298200Y521100D03*
X301300Y524400D03*
X355600Y513500D03*
X327300Y540100D03*
X341400Y560050D03*
X336881Y530496D03*
X307800Y546700D03*
X341615Y556015D03*
X336953Y534506D03*
X305913Y549643D03*
X331900Y549700D03*
X329050Y552315D03*
X348220Y563836D03*
X344812Y563844D03*
X344755Y497841D03*
X304436Y564081D03*
X341349Y563750D03*
X307350Y561290D03*
X335000Y497000D03*
X332698Y543738D03*
X330200Y535200D03*
X331000Y522100D03*
X302665Y547006D03*
X302506Y543341D03*
X327403Y543499D03*
X336723Y542000D03*
X327800Y514900D03*
X330200Y531800D03*
X323400Y507540D03*
X336800Y506300D03*
X286061Y502378D03*
X293970Y564927D03*
X335000Y500600D03*
X298719Y542538D03*
X293500Y522600D03*
X334811Y551476D03*
X311900Y511500D03*
X309600Y520150D03*
X312300Y540600D03*
X332940Y539287D03*
X333400Y503800D03*
X322900Y530600D03*
X327417Y548344D03*
X290000Y503200D03*
X293800Y503300D03*
X353500Y624500D03*
X353669Y600881D03*
X302300Y582000D03*
X286700Y611911D03*
X340920Y575234D03*
X348000Y612661D03*
X352472Y581000D03*
X325762Y596900D03*
X324900Y581600D03*
X291839Y578193D03*
X293697Y589566D03*
X289070Y573080D03*
X355700Y579317D03*
X341755Y627231D03*
Y623682D03*
X341600Y616962D03*
Y613413D03*
X334264Y602648D03*
X337813D03*
X352716Y594135D03*
X350746Y574837D03*
X293500Y625600D03*
X293600Y629100D03*
X321421Y605265D03*
X323413Y602491D03*
X303000Y586800D03*
X292006Y574797D03*
X315616Y571817D03*
X289800Y569182D03*
X315893Y567721D03*
X341558Y567689D03*
X300043Y603619D03*
X303468Y603647D03*
X352716Y590535D03*
X347784Y587509D03*
X336923Y586749D03*
X347784Y584109D03*
X336923Y583349D03*
X307650Y596000D03*
X285400Y572556D03*
X325761Y592959D03*
X315315Y575204D03*
X317813Y580469D03*
X286400Y569200D03*
X317813Y584969D03*
X325899Y589186D03*
X328356Y678679D03*
X297900Y664800D03*
X290600Y668200D03*
X338301Y673907D03*
X328600Y661100D03*
X343372Y655836D03*
X347013Y656090D03*
X328087Y701587D03*
X327062Y697600D03*
X332200Y643800D03*
X288720Y641455D03*
X289473Y657061D03*
X336000Y662200D03*
X336387Y648987D03*
X317516Y671612D03*
X315000Y674900D03*
X338135Y670511D03*
X342542Y685983D03*
X342645Y682506D03*
X300700Y667000D03*
X330593Y671019D03*
X303741Y654095D03*
X329989Y653920D03*
X291700Y737000D03*
X316465Y716063D03*
X287220Y737920D03*
X334000Y714640D03*
X293075Y726600D03*
X342208Y714950D03*
X337481Y719818D03*
X425765Y56265D03*
X372500Y44500D03*
Y56500D03*
X366500Y124700D03*
X363100Y124600D03*
X387833Y82930D03*
X391382D03*
X372500Y90000D03*
Y78000D03*
X396800Y74800D03*
X365800Y193750D03*
X399900Y152100D03*
X400924Y155896D03*
X404473D03*
X398000Y165400D03*
X398050Y162000D03*
X406400Y150300D03*
X363828Y243944D03*
X381009Y343909D03*
X380799Y347303D03*
X386250Y318250D03*
X380600Y335700D03*
X373700Y329700D03*
X376910Y366078D03*
X359323Y372277D03*
X363699Y382608D03*
X363703Y386008D03*
X363586Y375809D03*
X363701Y379208D03*
X377300Y362700D03*
X361250Y491650D03*
X363942Y450591D03*
X366700Y454800D03*
X359400Y451600D03*
X381276Y469106D03*
X374030Y449526D03*
X372575Y452600D03*
X380200Y457800D03*
X381400Y462000D03*
X387500Y458200D03*
X370800Y475128D03*
X389081Y475224D03*
X387950Y466800D03*
X394700Y481700D03*
X394952Y485300D03*
X378937Y443491D03*
X376697Y446050D03*
X373576Y466300D03*
X373534Y462830D03*
X370900Y471700D03*
X373700Y482700D03*
X378200Y476600D03*
X377691Y451891D03*
X381370Y465500D03*
X388123Y492432D03*
X378840Y448690D03*
X361013Y475128D03*
X372714Y509275D03*
X364000Y525500D03*
X387400Y547500D03*
X384400Y545195D03*
X362666Y504265D03*
X390651Y499000D03*
X387800Y525500D03*
X387700Y521600D03*
X376617Y544817D03*
X397650Y508250D03*
Y536671D03*
X362280Y554590D03*
X397650Y519400D03*
X394880Y548670D03*
X397650Y523900D03*
X393465Y553100D03*
X387700Y517700D03*
X362500Y499970D03*
X365730Y541050D03*
X368900Y505000D03*
X372494Y513020D03*
X383126Y565162D03*
X366490Y564360D03*
X370763Y547900D03*
X370800Y551300D03*
Y554700D03*
X383080Y554897D03*
X384347Y558647D03*
X382922Y561735D03*
X372900Y538700D03*
X396400Y545500D03*
X390769Y495379D03*
X393889Y543207D03*
X367133Y596067D03*
X382380Y612620D03*
X371180Y629236D03*
X386224Y580524D03*
X383411Y577024D03*
X362250Y570875D03*
X364300Y592900D03*
X384500Y616500D03*
X361227Y630300D03*
X378400Y594800D03*
X383313Y621780D03*
X365953Y570753D03*
X382600Y609000D03*
X375700Y580102D03*
X390600Y625500D03*
X366100Y590000D03*
X366500Y586300D03*
X380572Y592095D03*
X396300Y587000D03*
X396400Y583500D03*
X395127Y568056D03*
X395100Y572899D03*
X379100Y703300D03*
X363664Y688950D03*
X384466Y661650D03*
X378832Y659705D03*
X364600Y670800D03*
X388338Y643600D03*
Y647149D03*
X392100Y683900D03*
X392000Y679800D03*
X390500Y665800D03*
Y669200D03*
X396306Y698732D03*
X361914Y680181D03*
X401000Y676500D03*
X371457Y667593D03*
X368060Y667743D03*
X392079Y703434D03*
X396400Y659800D03*
X390355Y690926D03*
X373060Y702960D03*
X398600Y662700D03*
X383600Y711800D03*
X372100Y711700D03*
X472800Y50000D03*
X469000Y50100D03*
X499721Y46102D03*
X499623Y49524D03*
X446788Y55180D03*
X479040Y47134D03*
X458041Y47341D03*
X476100Y60500D03*
X478700Y62800D03*
X462372Y49179D03*
X486400Y38500D03*
X467016Y20430D03*
X450454Y38147D03*
X486527Y41939D03*
X447233Y48829D03*
X496355Y26000D03*
X496242Y22287D03*
X460300Y57600D03*
X432269Y19980D03*
X486700Y31100D03*
X462874Y95922D03*
X487500Y73400D03*
X485700Y70500D03*
X448000Y80404D03*
X444800Y82404D03*
X478590Y70310D03*
X482200Y70500D03*
X498500Y84200D03*
X471281Y105681D03*
X455766Y114535D03*
X473600Y108300D03*
X457000Y117800D03*
X480538Y112071D03*
X459500Y95500D03*
X441100Y110950D03*
X448996Y117666D03*
X463479Y99412D03*
X515700Y50899D03*
X515785Y55552D03*
X505633Y46932D03*
X502300Y58200D03*
X531050Y46998D03*
X528300Y58648D03*
X515500Y59000D03*
X513500Y62000D03*
X532500Y58600D03*
X543059Y108958D03*
X540800Y111500D03*
X501100Y86800D03*
X538456Y65144D03*
X509981Y103194D03*
X505779D03*
X513300Y83000D03*
X503700Y107600D03*
X599254Y37967D03*
X582447Y50607D03*
X586754Y53967D03*
X577847Y50807D03*
X582797Y31807D03*
X600847Y33907D03*
X588753Y24080D03*
X636647Y64300D03*
X642998Y127863D03*
X642574Y131843D03*
X685907Y30622D03*
X673647Y33107D03*
X680300Y17500D03*
X680000Y23900D03*
X675903Y29541D03*
X668531Y71500D03*
X713200Y387700D03*
X696070Y483486D03*
X712874Y470182D03*
X707391Y484208D03*
X712000Y442100D03*
X711300Y423800D03*
X701183Y453339D03*
X704836D03*
X709700Y480332D03*
X698651Y428165D03*
X669749Y458022D03*
X683000Y447200D03*
X680200Y449500D03*
X705450Y440950D03*
X705700Y493500D03*
X708367Y491000D03*
X708682Y551846D03*
X711156Y554320D03*
X699453Y551078D03*
X701927Y553552D03*
X686198Y552098D03*
X688672Y554572D03*
X684818Y543012D03*
X687292Y545486D03*
X671024Y544571D03*
X673498Y547045D03*
X657921Y539000D03*
X660395Y541474D03*
X653634Y513757D03*
X656846Y521702D03*
X678740Y508760D03*
X777500Y34500D03*
X766200Y22000D03*
X723800Y18600D03*
X718300Y387700D03*
X725200Y442100D03*
X740500Y431000D03*
X723800Y475164D03*
X788263Y554763D03*
X778763Y553763D03*
X781237Y556237D03*
X768263Y552763D03*
X770737Y555237D03*
X756263Y548263D03*
X758737Y550737D03*
X728682Y549946D03*
X731156Y552420D03*
X717829Y549856D03*
X720303Y552330D03*
X720536Y523519D03*
X724036D03*
X759342Y543603D03*
X765935Y537009D03*
X777165Y509835D03*
X845168Y192764D03*
X851137Y199864D03*
X858622Y155614D03*
X854634Y166390D03*
X842511Y164078D03*
X842022Y152174D03*
X857700Y222300D03*
X848868Y219064D03*
X835316Y340914D03*
X846456Y350814D03*
X831650Y422612D03*
X830531Y361589D03*
X794200Y422800D03*
X811300Y395900D03*
X801200Y386700D03*
X796100D03*
X821800Y400500D03*
X821700Y403900D03*
X842820Y382172D03*
X816997Y371022D03*
X847629Y391998D03*
X855320Y414472D03*
X830133Y353930D03*
X842916Y357214D03*
X849420Y407748D03*
X822300Y390000D03*
X811142Y470358D03*
X811668Y433703D03*
X820150Y433900D03*
X794900Y441100D03*
X808100D03*
X807400Y477229D03*
X823710Y469835D03*
X803300Y491600D03*
X806888Y491398D03*
X825263Y553263D03*
X827737Y555737D03*
X812763Y548263D03*
X815237Y550737D03*
X806763Y554763D03*
X809237Y557237D03*
X797763Y554263D03*
X800237Y556737D03*
X790737Y557237D03*
X842369Y549234D03*
X839895Y546760D03*
X867653Y172764D03*
X867851Y163585D03*
X864992Y175435D03*
X864492Y206435D03*
X860868Y219764D03*
X868433Y349134D03*
X864920Y368972D03*
X861420Y367269D03*
X861484Y399069D03*
G54D26*
X265400Y446100D03*
X468000Y31500D03*
Y39500D03*
X464000Y35500D03*
X468000Y35400D03*
X472000Y35500D03*
X753800Y535000D03*
G54D24*
X201801Y684252D03*
X225601D03*
G54D33*
X421653Y130709D03*
X428740Y125985D03*
X421653Y136221D03*
X428740Y131496D03*
X421653Y144882D03*
X428740Y140158D03*
X421653Y150394D03*
X428740Y145670D03*
X421653Y159055D03*
X428740Y154331D03*
X421653Y164567D03*
X428740Y159843D03*
X421653Y173229D03*
X428740Y168504D03*
X421653Y178740D03*
X428740Y174016D03*
X435827Y130709D03*
X442913Y125985D03*
X450000Y130709D03*
X457086Y125985D03*
X464173Y130709D03*
X471260Y125985D03*
X435827Y136221D03*
X442913Y131496D03*
X450000Y136221D03*
X457086Y131496D03*
X464173Y136221D03*
X471260Y131496D03*
X435827Y144882D03*
X442913Y140158D03*
X450000Y144882D03*
X457086Y140158D03*
X464173Y144882D03*
X471260Y140158D03*
X435827Y150394D03*
X442913Y145670D03*
X450000Y150394D03*
X457086Y145670D03*
X464173Y150394D03*
X471260Y145670D03*
X435827Y159055D03*
X442913Y154331D03*
X450000Y159055D03*
X457086Y154331D03*
X464173Y159055D03*
X471260Y154331D03*
X435827Y164567D03*
X442913Y159843D03*
X450000Y164567D03*
X457086Y159843D03*
X464173Y164567D03*
X471260Y159843D03*
X435827Y173229D03*
X442913Y168504D03*
X450000Y173229D03*
X457086Y168504D03*
X464173Y173229D03*
X471260Y168504D03*
X435827Y178740D03*
X442913Y174016D03*
X450000Y178740D03*
X457086Y174016D03*
X464173Y178740D03*
X471260Y174016D03*
X506693Y130709D03*
X513779Y125985D03*
X520866Y130709D03*
X527953Y125985D03*
X535039Y130709D03*
X542126Y125985D03*
X549212Y130709D03*
X556299Y125985D03*
X506693Y136221D03*
X513779Y131496D03*
X520866Y136221D03*
X527953Y131496D03*
X535039Y136221D03*
X542126Y131496D03*
X549212Y136221D03*
X556299Y131496D03*
X506693Y144882D03*
X513779Y140158D03*
X520866Y144882D03*
X527953Y140158D03*
X535039Y144882D03*
X542126Y140158D03*
X549212Y144882D03*
X556299Y140158D03*
X506693Y150394D03*
X513779Y145670D03*
X520866Y150394D03*
X527953Y145670D03*
X535039Y150394D03*
X542126Y145670D03*
X549212Y150394D03*
X556299Y145670D03*
X506693Y159055D03*
X513779Y154331D03*
X520866Y159055D03*
X527953Y154331D03*
X535039Y159055D03*
X542126Y154331D03*
X549212Y159055D03*
X556299Y154331D03*
X506693Y164567D03*
X513779Y159843D03*
X520866Y164567D03*
X527953Y159843D03*
X535039Y164567D03*
X542126Y159843D03*
X549212Y164567D03*
X556299Y159843D03*
X506693Y173229D03*
X513779Y168504D03*
X520866Y173229D03*
X527953Y168504D03*
X535039Y173229D03*
X542126Y168504D03*
X549212Y173229D03*
X556299Y168504D03*
X506693Y178740D03*
X513779Y174016D03*
X520866Y178740D03*
X527953Y174016D03*
X535039Y178740D03*
X542126Y174016D03*
X549212Y178740D03*
X556299Y174016D03*
G54D32*
X305906Y388386D03*
G54D22*
X103940Y635460D03*
X76118Y625275D03*
X81118D03*
X76549Y680547D03*
Y675547D03*
X81549Y680547D03*
Y675547D03*
X134223Y691027D03*
X122335Y660582D03*
Y655782D03*
X83125Y719240D03*
Y724040D03*
X155400Y717700D03*
X249200Y733700D03*
Y728700D03*
Y723700D03*
Y718700D03*
Y738500D03*
X334782Y184928D03*
X321182Y202574D03*
Y197774D03*
X305882Y195474D03*
X305382Y190174D03*
X334882Y195478D03*
Y200478D03*
Y190478D03*
X335061Y222578D03*
X335100Y218378D03*
X323492Y214234D03*
X305862Y210014D03*
X322000Y653081D03*
X312400D03*
X317200D03*
X307600D03*
X298700Y674600D03*
X303700D03*
X305559Y720973D03*
X310559D03*
X305559Y725973D03*
X310559D03*
X299500Y725400D03*
X373073Y201889D03*
X435000Y29000D03*
X438500Y25500D03*
Y32500D03*
X491500Y71600D03*
X496500D03*
X491500Y76600D03*
X496500D03*
X516693Y46345D03*
X521493D03*
X516693Y41545D03*
X521493D03*
Y36745D03*
X516693D03*
X521493Y31945D03*
X526530Y43775D03*
X516693Y31945D03*
X567700Y28240D03*
X506500Y76600D03*
X501500D03*
Y71600D03*
X593017Y69796D03*
X588217Y74596D03*
Y69796D03*
X653601Y46761D03*
X658601D03*
X653601Y51761D03*
X658601D03*
X663601Y46761D03*
Y51761D03*
X668601Y46761D03*
Y51761D03*
X649590Y114036D03*
X689875Y464586D03*
X698275Y438305D03*
X683100Y485200D03*
X679832Y494100D03*
Y489100D03*
X679100Y483300D03*
X674900D03*
X674832Y489100D03*
Y494100D03*
X682800Y480700D03*
X736217Y493664D03*
X776658Y489380D03*
X771658D03*
X781658D03*
Y494380D03*
X741217Y493664D03*
X776658Y494380D03*
X771658D03*
X752602Y517850D03*
X736580Y507734D03*
X788015Y507785D03*
X783015D03*
X747602Y517850D03*
X731580Y507734D03*
X716578Y509762D03*
X721590Y511659D03*
X726590D03*
X857965Y273150D03*
X859407Y300314D03*
Y309914D03*
Y305114D03*
Y295314D03*
Y290314D03*
Y285314D03*
X809000Y429400D03*
X840057Y494320D03*
X835057D03*
X836023Y508124D03*
X825161Y507954D03*
X820161D03*
X815161D03*
X805983Y508293D03*
X793015Y507785D03*
X897250Y81510D03*
X902050D03*
Y86310D03*
X897250D03*
Y91110D03*
X902050D03*
X897250Y95910D03*
X902050D03*
X880222Y206781D03*
X875222D03*
X896031Y228468D03*
Y223468D03*
X891031D03*
Y228468D03*
Y238468D03*
X896031D03*
X891031Y233468D03*
X896031D03*
X868376Y271313D03*
X873376D03*
X880122Y216781D03*
X875122D03*
X880222Y211781D03*
X875222D03*
X864207Y300314D03*
Y309914D03*
Y305114D03*
Y295314D03*
Y290314D03*
Y285314D03*
X902091Y369397D03*
X897091D03*
X902091Y374397D03*
X897091D03*
Y379397D03*
X902091D03*
X888548Y392923D03*
X883548D03*
X893548D03*
X888548Y387923D03*
X893548D03*
X883548D03*
G54D37*
X666929Y510236D03*
X765354D03*
G54D40*
X801024Y24409D03*
X821024D03*
G54D23*
X168898Y548819D03*
X165745Y564567D03*
X168895D03*
X159449Y561417D03*
X165748D03*
X172047D03*
X162598Y558268D03*
X168898D03*
X165748Y555118D03*
X159449D03*
X162599Y551970D03*
X194093D03*
X197243D03*
X181497D03*
X175197D03*
X178347D03*
X203542Y555120D03*
X187795D03*
X200393Y551970D03*
X206692Y558269D03*
Y561419D03*
Y564569D03*
X175196Y558269D03*
X190945Y545669D03*
X172047D03*
Y551970D03*
X159449Y545671D03*
X162599Y545669D03*
X165749D03*
X212991Y561419D03*
X184646Y548821D03*
Y545671D03*
X184645Y542519D03*
X206693Y542520D03*
X159449Y542521D03*
X171906Y534661D03*
X212991Y542519D03*
X156299Y545671D03*
X165749Y548819D03*
X175197Y545671D03*
X162599Y542519D03*
X168898D03*
X156299Y542521D03*
X181496Y542520D03*
X159449Y548821D03*
X194094Y542519D03*
X172047Y548819D03*
X168898Y551969D03*
X162599Y548821D03*
X162598Y561417D03*
X168898Y555119D03*
X181497Y548821D03*
X178346Y545670D03*
X181497Y545671D03*
X162595Y564567D03*
X203542Y551970D03*
X181497Y555120D03*
X178346Y555119D03*
X187885Y552058D03*
X197245Y555118D03*
X159412Y552006D03*
X165748Y551968D03*
X178347Y564569D03*
X203543Y561418D03*
Y564568D03*
X172047D03*
X200393Y548819D03*
X209842Y545669D03*
Y564567D03*
Y558268D03*
X212992Y551969D03*
Y548819D03*
X209842Y561417D03*
X212992Y564567D03*
X200393Y545669D03*
X206692Y545671D03*
X209842Y548819D03*
X212992Y545669D03*
X165777Y542555D03*
X209842Y555119D03*
Y551969D03*
X206692Y548820D03*
X206693Y551969D03*
X194094Y545669D03*
Y548820D03*
X175197Y548821D03*
X168898Y545669D03*
X153150Y539371D03*
X153149Y542521D03*
X197244Y545669D03*
Y542519D03*
X156300Y539371D03*
X197243Y589900D03*
X194094Y602362D03*
X206692Y596063D03*
X203450Y592912D03*
X194093Y596063D03*
X172020Y577050D03*
X212991Y567718D03*
X209841Y574016D03*
X206692D03*
X168898Y567717D03*
X159449Y570866D03*
X168898Y583464D03*
Y577165D03*
X159449Y586614D03*
X162598Y580315D03*
Y586614D03*
X165748D03*
X168898D03*
X159449Y577165D03*
X156299D03*
X168898Y580315D03*
X159449D03*
X162598Y577165D03*
X165748Y580315D03*
X162598Y583464D03*
X165748Y570866D03*
Y567717D03*
X162598D03*
X172047Y570867D03*
X194094Y577166D03*
X203543Y574017D03*
X178347Y589764D03*
X181497D03*
X194093Y586614D03*
X209841Y596063D03*
X206692Y583465D03*
Y567600D03*
X212992Y580315D03*
X212991Y577165D03*
X209842Y567717D03*
X212991Y574016D03*
X190945Y599213D03*
X190944Y596063D03*
X187796Y599212D03*
X181586Y599123D03*
X212991Y583465D03*
X209841Y577165D03*
X159448Y596063D03*
X190944Y602362D03*
X203543D03*
X203542Y596063D03*
X194094Y599213D03*
X168898Y596063D03*
X212992Y602363D03*
X212991Y599212D03*
X206692Y589763D03*
X168898Y592913D03*
X162598Y596063D03*
X194093Y589764D03*
Y592913D03*
X206692Y586614D03*
X209842Y586613D03*
X212992Y589764D03*
X209841Y592913D03*
X162598Y570866D03*
X178347Y574018D03*
X203542Y580315D03*
Y586614D03*
X190944D03*
X178346Y586615D03*
X181497Y586614D03*
X178344Y577166D03*
X203542Y577165D03*
X178347Y570769D03*
X203501Y571005D03*
X175298Y577266D03*
X172047Y567717D03*
X178346Y596064D03*
X178347Y599213D03*
X165748D03*
X168898D03*
X162598D03*
X159448D03*
X172048Y596063D03*
X190944Y592913D03*
Y589764D03*
X200393Y586614D03*
X197165Y586540D03*
X212993Y592912D03*
X209842Y589763D03*
X206692Y580315D03*
X209841D03*
X181500Y595900D03*
X200393Y592912D03*
X209841Y599212D03*
X200393D03*
X159448Y589764D03*
Y592913D03*
X162598Y589764D03*
X165748D03*
Y596063D03*
Y592913D03*
X175197D03*
X172048D03*
X181530Y592765D03*
X175197Y596063D03*
Y599213D03*
X172048D03*
X216141Y564569D03*
Y561419D03*
X219291Y542519D03*
X216141D03*
X216142Y548820D03*
X216141Y555120D03*
Y558269D03*
X222441Y548820D03*
X219291D03*
X216141Y551970D03*
X216142Y545669D03*
X216141Y580315D03*
Y577165D03*
Y583465D03*
Y586614D03*
Y567718D03*
X219293Y567717D03*
X216141Y574016D03*
Y599212D03*
Y589762D03*
X230600Y608100D03*
G54D39*
X745669Y510236D03*
X844094D03*
G54D28*
X353543Y62913D03*
Y55039D03*
X346457Y66850D03*
Y74724D03*
Y84567D03*
X353543Y86535D03*
Y78661D03*
Y70787D03*
G54D31*
X305906Y182874D03*
G54D10*
X61024Y34449D03*
X33464D03*
X38386Y24606D03*
X108268Y44292D03*
X80708D03*
X85630Y34449D03*
G54D18*
X67853Y573865D03*
X99337Y683756D03*
Y678756D03*
Y673756D03*
X95200Y667500D03*
X90400D03*
X85600D03*
X190944Y577166D03*
X187795D03*
X307567Y273592D03*
X304548Y272508D03*
Y261008D03*
X334107Y291354D03*
Y279854D03*
X307567Y349192D03*
X304267Y348092D03*
Y336592D03*
X307567Y335492D03*
Y323992D03*
X304267Y322892D03*
Y311392D03*
X307567Y310292D03*
Y298792D03*
X304267Y297692D03*
Y286192D03*
X334582Y341721D03*
Y330221D03*
X328187Y342816D03*
X328182Y329124D03*
Y317624D03*
X334593Y316584D03*
Y305084D03*
X328182Y303977D03*
Y292477D03*
X307567Y285092D03*
X304267Y373292D03*
Y361792D03*
X307567Y360692D03*
X328182Y379518D03*
Y368018D03*
X334582Y366974D03*
Y355474D03*
X328187Y354316D03*
X335000Y621200D03*
Y615400D03*
Y610200D03*
X325600Y640100D03*
X330400D03*
X335200D03*
X315520Y711720D03*
X320320D03*
X325120D03*
X588647Y28007D03*
X603943Y42806D03*
X608143Y42906D03*
X603943Y47006D03*
X608043D03*
X603747Y71407D03*
X900600Y201239D03*
G54D42*
X845198Y552063D03*
X837066Y543931D03*
G54D12*
X66435Y8514D03*
X61435D03*
X56435D03*
X51435D03*
X46435D03*
X41435D03*
X36435D03*
X31435D03*
X26435D03*
X21435D03*
X16435D03*
X8514Y10593D03*
Y15593D03*
Y20593D03*
Y25593D03*
Y30593D03*
Y35593D03*
Y40593D03*
Y45593D03*
Y50593D03*
Y55593D03*
Y60593D03*
X43000Y59500D03*
X51000D03*
X34000Y59400D03*
X8514Y65593D03*
Y70593D03*
Y75593D03*
Y80593D03*
Y85593D03*
Y90593D03*
Y95593D03*
Y100593D03*
Y105593D03*
Y110593D03*
Y115593D03*
Y120593D03*
Y125593D03*
Y130593D03*
Y135593D03*
Y140593D03*
Y145593D03*
Y150593D03*
Y155593D03*
Y160593D03*
Y165593D03*
Y170593D03*
Y175593D03*
Y180593D03*
Y185593D03*
Y190593D03*
Y195593D03*
Y200593D03*
Y205593D03*
Y210593D03*
Y215593D03*
Y220593D03*
Y225593D03*
Y230593D03*
Y235593D03*
Y240593D03*
Y245593D03*
Y250593D03*
Y255593D03*
Y260593D03*
Y265593D03*
Y270593D03*
Y275593D03*
Y280593D03*
Y285593D03*
Y290593D03*
Y295593D03*
Y300593D03*
Y305593D03*
Y310593D03*
Y315593D03*
Y320593D03*
Y325593D03*
Y330593D03*
Y335593D03*
Y340593D03*
Y345593D03*
Y350593D03*
Y355593D03*
Y360593D03*
Y365593D03*
Y370593D03*
Y375593D03*
Y380593D03*
Y385593D03*
Y390593D03*
Y395593D03*
Y400593D03*
Y405593D03*
Y410593D03*
Y415593D03*
Y420593D03*
Y425593D03*
Y430593D03*
Y435593D03*
Y440593D03*
Y445593D03*
Y450593D03*
Y455593D03*
Y460593D03*
Y465593D03*
Y470593D03*
Y475593D03*
Y480593D03*
Y485593D03*
Y490593D03*
Y495593D03*
Y500593D03*
Y505593D03*
Y510593D03*
Y515593D03*
Y520593D03*
Y525593D03*
Y530593D03*
Y535593D03*
Y540593D03*
Y545593D03*
Y550593D03*
Y555593D03*
Y560593D03*
Y565593D03*
X37660Y566400D03*
X64427Y538836D03*
X64701Y564416D03*
X61100Y546700D03*
X8514Y570593D03*
Y575593D03*
Y580593D03*
Y585593D03*
Y590593D03*
Y595593D03*
Y600593D03*
Y605593D03*
Y610593D03*
Y615593D03*
Y620593D03*
Y625593D03*
Y630593D03*
Y635593D03*
X42597Y571789D03*
X64701Y570716D03*
X8514Y640593D03*
Y645593D03*
Y650593D03*
Y655593D03*
Y660593D03*
Y665593D03*
Y670593D03*
Y675593D03*
Y680593D03*
Y685593D03*
Y690593D03*
Y695593D03*
Y700593D03*
Y705593D03*
Y710593D03*
X50400Y663700D03*
X50500Y667900D03*
X60600Y670900D03*
X65900Y671000D03*
X65714Y665850D03*
X60800Y660900D03*
X60700Y665900D03*
X65700Y660900D03*
X64884Y650984D03*
X37961Y659909D03*
X41100Y671800D03*
X8514Y715593D03*
Y720593D03*
X9942Y725256D03*
X12178Y729728D03*
X14414Y734200D03*
X16650Y738672D03*
X18886Y743144D03*
X21122Y747617D03*
X23358Y752089D03*
X111683Y63266D03*
Y58266D03*
Y23266D03*
Y18266D03*
Y13266D03*
X111435Y8514D03*
X106435D03*
X101435D03*
X96435D03*
X91435D03*
X86435D03*
X81435D03*
X76435D03*
X71435D03*
X111683Y118266D03*
Y113266D03*
Y108266D03*
Y103266D03*
Y98266D03*
Y93266D03*
Y88266D03*
Y83266D03*
Y78266D03*
Y73266D03*
Y68266D03*
X90768Y69755D03*
X82768D03*
X73768Y69655D03*
X111683Y203266D03*
Y198266D03*
Y193266D03*
Y188266D03*
Y183266D03*
Y178266D03*
Y173266D03*
Y168266D03*
Y163266D03*
Y158266D03*
Y153266D03*
Y148266D03*
Y278266D03*
Y273266D03*
Y268266D03*
Y263266D03*
Y258266D03*
Y253266D03*
Y248266D03*
Y243266D03*
Y238266D03*
Y233266D03*
Y228266D03*
Y223266D03*
Y218266D03*
Y213266D03*
Y208266D03*
Y348266D03*
Y343266D03*
Y338266D03*
Y333266D03*
Y328266D03*
Y323266D03*
Y318266D03*
Y313266D03*
Y308266D03*
Y303266D03*
Y298266D03*
Y293266D03*
Y288266D03*
Y283266D03*
Y418266D03*
Y413266D03*
Y408266D03*
Y403266D03*
Y398266D03*
Y393266D03*
Y388266D03*
Y383266D03*
Y378266D03*
Y373266D03*
Y368266D03*
Y363266D03*
Y358266D03*
Y353266D03*
X104000Y475500D03*
X105350Y511850D03*
X89899Y564415D03*
X119400Y511500D03*
X135012Y510200D03*
X94473Y547093D03*
X138900Y525999D03*
X136974Y534479D03*
X120500Y504600D03*
X140400Y607850D03*
X137000D03*
X130700D03*
X135706Y621187D03*
X119900Y621000D03*
X131200Y620600D03*
X89901Y587466D03*
X85400Y629784D03*
X86300Y703200D03*
Y708000D03*
X127100Y647000D03*
X123100D03*
X119000D03*
X139916Y709422D03*
X130019Y709695D03*
X139916Y705822D03*
X130019Y706095D03*
X135019D03*
X70700Y671000D03*
X70800Y660700D03*
X70600Y665800D03*
X73427Y699285D03*
X104550Y647050D03*
X104850Y639150D03*
X111300Y705500D03*
X76395Y755266D03*
X81395D03*
X86395D03*
X91395D03*
X96395D03*
X101395D03*
X106395D03*
X111395D03*
X116395D03*
X121395D03*
X126395D03*
X131395D03*
X136395D03*
X141395D03*
X108928Y744775D03*
X113928D03*
X118928D03*
X123928D03*
X103928D03*
X98928D03*
X93928D03*
X139916Y713022D03*
Y716622D03*
Y720222D03*
Y723822D03*
X130019Y713295D03*
Y716895D03*
Y720495D03*
X135019Y710595D03*
Y723595D03*
Y719095D03*
Y714845D03*
X130019Y724095D03*
X148000Y469000D03*
X196100Y482200D03*
X170870Y492270D03*
X198700Y513500D03*
X203350Y506700D03*
X188600Y531500D03*
X203500Y513500D03*
X191398Y509000D03*
X156297Y558267D03*
X211700Y513500D03*
X208700Y529100D03*
X207500Y502412D03*
X145000Y497600D03*
X200963Y636600D03*
X212923Y615000D03*
X191210Y617900D03*
X203300Y628900D03*
X196700Y704985D03*
X201700D03*
X206700D03*
X211700D03*
X191700D03*
X166500Y640300D03*
X191766Y679920D03*
X211706Y645349D03*
X208200Y645500D03*
X151130Y703440D03*
X184807Y643963D03*
X188500Y686800D03*
X146395Y755266D03*
X151395D03*
X156395D03*
X161395D03*
X166395D03*
X171395D03*
X176395D03*
X181395D03*
X186395D03*
X191395D03*
X196395D03*
X201395D03*
X206395D03*
X211395D03*
X213900Y474650D03*
X227100Y490300D03*
X275300Y467300D03*
X234648Y540453D03*
X221960Y504230D03*
X222500Y536161D03*
X279600Y527900D03*
X279450Y577970D03*
X260850Y603537D03*
X274800Y607500D03*
X258600Y613100D03*
X254208Y603995D03*
X254043Y598359D03*
X247088Y610236D03*
X254821Y627000D03*
X255228Y631071D03*
X278150Y637250D03*
X229800Y593200D03*
X246800Y589600D03*
X261900Y588900D03*
X245400Y581800D03*
X264358Y608152D03*
X241300Y635900D03*
X228900Y635800D03*
X222500Y630200D03*
X218800Y635600D03*
X221800Y614800D03*
X246500Y602500D03*
X234000Y628400D03*
X230900Y581600D03*
X270300Y622315D03*
X281500Y598419D03*
X221700Y704985D03*
X226700D03*
X216700D03*
X267500Y645600D03*
X280500Y708100D03*
X269003Y704337D03*
X282620Y640950D03*
X262826Y662274D03*
X245100Y639500D03*
X219200Y645300D03*
X230270Y645933D03*
X247725Y656375D03*
X261900Y699300D03*
X266550Y675750D03*
X247825Y670375D03*
X245971Y698400D03*
X235100Y679921D03*
X221575Y695400D03*
X279400Y686400D03*
X216395Y755266D03*
X221395D03*
X226395D03*
X231395D03*
X236395D03*
X241395D03*
X246395D03*
X251395D03*
X256395D03*
X261395D03*
X266395D03*
X271395D03*
X276395D03*
X281395D03*
X280600Y711700D03*
X282353Y740020D03*
X268820Y715100D03*
X262645Y712155D03*
X330546Y8514D03*
X325546D03*
X320546D03*
X315546D03*
X310546D03*
X305546D03*
X300546D03*
X296034Y9002D03*
Y14002D03*
Y19002D03*
Y24002D03*
Y29002D03*
Y34002D03*
Y39002D03*
Y44002D03*
Y49002D03*
Y54002D03*
Y59002D03*
Y64002D03*
Y69002D03*
Y74002D03*
Y79002D03*
Y84002D03*
Y89002D03*
Y94002D03*
Y99002D03*
Y104002D03*
Y109002D03*
Y114002D03*
Y119002D03*
Y124002D03*
Y129002D03*
Y134002D03*
X345069Y108533D03*
X340080Y108432D03*
X348900Y115400D03*
X340706Y128612D03*
X305703Y202696D03*
X355600Y172900D03*
X306407Y206057D03*
X355300Y179300D03*
X354282Y187718D03*
Y191718D03*
X296034Y139002D03*
X321432Y279090D03*
X321281Y266486D03*
X321197Y254433D03*
X306446Y247874D03*
X323842Y219284D03*
X305498Y213824D03*
X305382Y227474D03*
X323800Y227000D03*
X323700Y230600D03*
X321432Y342082D03*
Y329484D03*
Y316885D03*
X321882Y304374D03*
Y291874D03*
X320832Y367479D03*
X321432Y354681D03*
X320932Y377074D03*
X340606Y389899D03*
X305350Y514300D03*
X292200Y542473D03*
X285800Y549394D03*
X346440Y527500D03*
X350879Y520400D03*
X352734Y541826D03*
X355700Y510000D03*
X344600Y511800D03*
X326900Y507700D03*
X312289Y535181D03*
X318200Y522900D03*
X299100Y589200D03*
X341750Y630790D03*
X342330Y620300D03*
X344940Y617720D03*
X292400Y637000D03*
X341690Y609930D03*
X341210Y602420D03*
X330800Y602610D03*
X317572Y603183D03*
X305470Y623734D03*
X311386Y633450D03*
X306300Y638600D03*
X301286Y638650D03*
X301386Y633650D03*
X306286D03*
X311186Y638550D03*
X307542Y588138D03*
X297118Y668882D03*
X294804Y695204D03*
X292400Y640500D03*
X332824Y684270D03*
X348314Y643853D03*
X332800Y691970D03*
X318000Y678270D03*
X304100Y666500D03*
X300720Y704920D03*
X300520Y710020D03*
X290620Y710120D03*
X295634Y710070D03*
X290720Y705120D03*
X295620D03*
X351547Y645938D03*
X355100Y651827D03*
X301186Y643650D03*
X306486Y643750D03*
X311286D03*
X314398Y670254D03*
X340000Y662200D03*
X352800Y702960D03*
X286395Y755266D03*
X291395D03*
X296395D03*
X301395D03*
X306395D03*
X311395D03*
X316395D03*
X321395D03*
X326395D03*
X331395D03*
X336395D03*
X298570Y743670D03*
X306470Y743570D03*
X300620Y715220D03*
X290520Y715120D03*
X295820Y715220D03*
X380500Y33500D03*
Y30000D03*
X382631Y48200D03*
X382547Y52800D03*
X375300Y62150D03*
X384000Y30000D03*
X375300Y72050D03*
X357500Y104200D03*
X394070Y80840D03*
X385964Y80089D03*
X382500Y88000D03*
X363400Y115950D03*
X376000Y78400D03*
X428740Y179528D03*
X405100Y159300D03*
X400000Y159200D03*
X365900Y198500D03*
X362150Y214174D03*
X364000Y240100D03*
X379448Y487250D03*
X368100Y513100D03*
X387800Y529400D03*
X367500Y526800D03*
X393100Y564400D03*
X362801Y548097D03*
X366900Y499942D03*
X365164Y612620D03*
X358864D03*
X396200Y597200D03*
X394800Y609700D03*
X358646Y596456D03*
X371400Y606400D03*
X358800Y606300D03*
X365300Y606500D03*
X371400Y612700D03*
X371300Y618800D03*
X365500Y619000D03*
X358900Y618800D03*
X359000Y635600D03*
X360980Y582586D03*
X394300Y576600D03*
X372951Y576851D03*
X377714Y631280D03*
X368399Y567372D03*
X399754Y706071D03*
X388418Y650549D03*
X385700Y641300D03*
X374200Y645871D03*
X374252Y641029D03*
X386050Y701200D03*
X389168Y743572D03*
X391404Y739100D03*
X393640Y734628D03*
X395876Y730156D03*
X398112Y725684D03*
X399754Y716071D03*
Y711071D03*
X379450Y714400D03*
X478426Y20427D03*
X496394Y30000D03*
X482727Y41870D03*
X486535Y47449D03*
X482397Y52176D03*
X457086Y179528D03*
X442913D03*
X471260D03*
X556510Y53626D03*
X504900Y18200D03*
X508646Y18386D03*
X518890Y59730D03*
X548550Y76480D03*
X525000Y76300D03*
X525200Y80900D03*
X513379Y103325D03*
X502379Y103194D03*
X556710Y64726D03*
X543750Y76480D03*
X513779Y179528D03*
X527953D03*
X542126D03*
X556299D03*
X608847Y34607D03*
X614032Y33307D03*
X621747Y63307D03*
X626647Y77507D03*
Y72507D03*
Y67507D03*
X576624Y193205D03*
Y198205D03*
Y203205D03*
Y208205D03*
Y213205D03*
Y223205D03*
Y228205D03*
Y233205D03*
Y238205D03*
Y243205D03*
Y248205D03*
Y253205D03*
Y258205D03*
Y263205D03*
Y268205D03*
Y273205D03*
Y278205D03*
Y333205D03*
Y338205D03*
Y343205D03*
Y348205D03*
Y353205D03*
Y358205D03*
Y363205D03*
Y368205D03*
Y373205D03*
Y378205D03*
Y383205D03*
Y388205D03*
Y393205D03*
Y398205D03*
Y403205D03*
Y408205D03*
Y413205D03*
Y418205D03*
Y423205D03*
Y428205D03*
Y433205D03*
Y438205D03*
Y443205D03*
Y448205D03*
Y498205D03*
Y503205D03*
Y508205D03*
Y513205D03*
Y518205D03*
Y523205D03*
Y528205D03*
Y533205D03*
Y538205D03*
Y543205D03*
Y548205D03*
Y553205D03*
Y558205D03*
Y563205D03*
Y568205D03*
Y573205D03*
Y578205D03*
Y583205D03*
Y588205D03*
X578710Y592712D03*
X580946Y597184D03*
X583182Y601656D03*
X585418Y606129D03*
X587654Y610601D03*
X635975Y621407D03*
X640975D03*
X715546Y8514D03*
X710546D03*
X705546D03*
X700546D03*
X695546D03*
X710550Y18550D03*
X700065Y135985D03*
Y125985D03*
Y115985D03*
X710065D03*
Y125985D03*
Y135985D03*
X700065Y155985D03*
X710065D03*
Y145985D03*
X696159Y225829D03*
X698909Y278104D03*
X700065Y265985D03*
Y255985D03*
Y245985D03*
Y235985D03*
X710065D03*
Y245985D03*
Y255985D03*
Y265985D03*
X709625Y275991D03*
X710065Y325985D03*
Y315985D03*
X711574Y285985D03*
X708307Y295429D03*
X710065Y305985D03*
Y335985D03*
Y345985D03*
X700065Y385985D03*
Y395985D03*
Y405985D03*
Y415985D03*
X710065Y375985D03*
Y355985D03*
Y365985D03*
Y455985D03*
X684399Y466984D03*
Y471984D03*
X706275Y445986D03*
X663500Y484000D03*
Y489000D03*
Y494000D03*
X692282Y476720D03*
X700900Y423800D03*
X693392Y520482D03*
X683392D03*
X688392D03*
X705080Y521247D03*
X694272Y495786D03*
X713189Y524511D03*
X707283D03*
X701378D03*
X695472D03*
X689567D03*
X683661D03*
X677756D03*
X662400Y519500D03*
X666800D03*
X657199Y530195D03*
X671850Y524511D03*
X645975Y621407D03*
X650975D03*
X655975D03*
X660975D03*
X665975D03*
X670975D03*
X675975D03*
X680975D03*
X685975D03*
X690975D03*
X695975D03*
X700975D03*
X705975D03*
X710975D03*
X715975D03*
X785546Y8514D03*
X780546D03*
X775546D03*
X770546D03*
X765546D03*
X760546D03*
X755546D03*
X750546D03*
X745546D03*
X740546D03*
X735546D03*
X730546D03*
X725546D03*
X720546D03*
X770065Y55985D03*
Y65985D03*
Y75985D03*
X750065Y85985D03*
X770065D03*
X760065D03*
X740065D03*
X730065Y95985D03*
X760065D03*
X780065D03*
X770065D03*
Y105985D03*
X780065D03*
Y115985D03*
X730065Y135985D03*
Y125985D03*
Y115985D03*
Y105985D03*
X750065Y95985D03*
X740065D03*
X750065Y105985D03*
X760065D03*
X740065D03*
X750065Y115985D03*
X760065D03*
X770065D03*
X740065D03*
X750065Y125985D03*
X760065D03*
X770065D03*
X780065D03*
X740065D03*
X750065Y135985D03*
X760065D03*
X770065D03*
X780065D03*
X740065D03*
X720065Y105985D03*
Y115985D03*
Y125985D03*
Y135985D03*
Y155985D03*
X780065D03*
X730065D03*
Y145985D03*
X750065D03*
X760065D03*
X770065D03*
X780065D03*
X740065D03*
X750065Y155985D03*
X760065D03*
X770065D03*
X740065D03*
X750065Y165985D03*
X760065D03*
X770065D03*
X740065D03*
X750065Y175985D03*
X760065D03*
X770065D03*
X740065D03*
X750065Y185985D03*
X760065D03*
X770065D03*
X740065D03*
X750065Y195985D03*
X760065D03*
X770065D03*
X740065D03*
X750065Y205985D03*
X760065D03*
X770065D03*
X740065D03*
X720065Y145985D03*
X730065Y215985D03*
X773469Y277001D03*
X780065Y275985D03*
X787817Y275879D03*
X750065Y215985D03*
X760065D03*
X770065D03*
X780065D03*
X740065D03*
X780065Y265985D03*
Y255985D03*
Y245985D03*
Y235985D03*
Y225985D03*
X770065Y265985D03*
Y255985D03*
Y245985D03*
Y235985D03*
Y225985D03*
X763133Y275881D03*
X759790Y263326D03*
X760065Y255985D03*
Y245985D03*
Y235985D03*
Y225985D03*
X750065Y275985D03*
Y265985D03*
Y255985D03*
Y245985D03*
Y235985D03*
Y225985D03*
X741608Y277171D03*
X740065Y265985D03*
Y255985D03*
Y245985D03*
Y235985D03*
Y225985D03*
X730830Y276087D03*
X730065Y265985D03*
Y255985D03*
X731766Y246017D03*
X730065Y235985D03*
X730190Y223549D03*
X720237Y223228D03*
X720065Y235985D03*
X721766Y246017D03*
X720065Y255985D03*
Y265985D03*
X718617Y275736D03*
X770065Y335985D03*
X760065D03*
X720065Y325985D03*
X760065D03*
X750065D03*
X740065D03*
X730065D03*
X720065Y315985D03*
X780065Y285985D03*
X770065D03*
X760065D03*
X750065Y295985D03*
X760065D03*
X770065D03*
X780065D03*
Y305985D03*
Y315985D03*
Y325985D03*
Y335985D03*
Y345985D03*
X770065Y305985D03*
Y315985D03*
Y325985D03*
Y345985D03*
X760065Y305985D03*
Y315985D03*
Y345985D03*
X750065Y305985D03*
Y315985D03*
Y335985D03*
Y345985D03*
X740065Y305985D03*
Y315985D03*
Y335985D03*
Y345985D03*
X730065D03*
Y335985D03*
Y315985D03*
X752500Y286000D03*
X740065Y295985D03*
X741000Y286000D03*
X730065Y305985D03*
X729486Y296094D03*
X729294Y285987D03*
X721574Y285985D03*
X719049Y296011D03*
X720065Y305985D03*
Y335985D03*
Y345985D03*
X750065Y415985D03*
X760065D03*
X770065D03*
X780065D03*
X730065D03*
X740065D03*
X750065Y405985D03*
X760065D03*
X770065D03*
X780065D03*
X730065D03*
X740065D03*
X780065Y395985D03*
X770065D03*
X760065D03*
X750065D03*
X740065D03*
X730065D03*
X720065Y375985D03*
X730065Y365985D03*
Y375985D03*
Y385985D03*
X750065D03*
X760065D03*
X770065D03*
X780065D03*
X740065D03*
X750065Y375985D03*
X760065D03*
X770065D03*
X780065D03*
X740065D03*
X750065Y365985D03*
X760065D03*
X770065D03*
X780065D03*
X740065D03*
X780065Y355985D03*
X770065D03*
X760065D03*
X750065D03*
X740065D03*
X730065D03*
X720065D03*
Y365985D03*
X783800Y422800D03*
X720065Y455985D03*
Y465985D03*
X750065D03*
X760065D03*
X770065D03*
X780065D03*
X730065D03*
X740065D03*
X780065Y455985D03*
X770065D03*
X760065D03*
X750065D03*
X740065D03*
X730065D03*
X750065Y445985D03*
X760065D03*
X770065D03*
X780065D03*
X730065D03*
X740065D03*
X750065Y435985D03*
X760065D03*
X770065D03*
X780065D03*
X740065D03*
X750065Y425985D03*
X760065D03*
X770065D03*
X780065D03*
X784604Y519082D03*
X758512Y534430D03*
X747107Y536580D03*
X739334Y524156D03*
X762679Y535537D03*
X742716Y536435D03*
X738779D03*
X782086D03*
X776181D03*
X770275D03*
X725000D03*
X719394Y536305D03*
X720975Y621407D03*
X725975D03*
X730975D03*
X735975D03*
X740975D03*
X745975D03*
X750975D03*
X755975D03*
X760975D03*
X765975D03*
X770975D03*
X775975D03*
X780975D03*
X785975D03*
X850546Y8514D03*
X845546D03*
X840546D03*
X835546D03*
X830546D03*
X825546D03*
X820546D03*
X815546D03*
X810546D03*
X805546D03*
X800546D03*
X795546D03*
X790546D03*
X820065Y105985D03*
Y135985D03*
Y125985D03*
Y115985D03*
X810065Y135985D03*
Y125985D03*
Y115985D03*
X790065Y105985D03*
X800065Y115985D03*
X790065D03*
Y125985D03*
X800065D03*
Y135985D03*
X790065D03*
X853436Y108917D03*
Y113717D03*
X853435Y90260D03*
Y95060D03*
X820065Y155985D03*
X810065D03*
X800065D03*
X790065D03*
X820065Y145985D03*
X810065D03*
X790065D03*
X800065D03*
X820313Y276188D03*
X810065Y275985D03*
X800065D03*
X820065Y265985D03*
Y255985D03*
Y245985D03*
Y235985D03*
Y225985D03*
X810065Y265985D03*
Y255985D03*
Y245985D03*
Y235985D03*
X800065Y265985D03*
Y255985D03*
Y245985D03*
Y235985D03*
X790065Y265985D03*
Y255985D03*
Y245985D03*
Y235985D03*
Y225985D03*
X820065Y305985D03*
Y295985D03*
Y285985D03*
X810065Y295985D03*
Y285985D03*
X800065D03*
X790065D03*
Y295985D03*
X800065D03*
X810065Y305985D03*
X810000Y314000D03*
X810065Y325985D03*
X800065Y305985D03*
Y315985D03*
Y325985D03*
Y335985D03*
Y345985D03*
X790065Y305985D03*
Y315985D03*
Y325985D03*
X791500Y336000D03*
X790065Y345985D03*
Y415985D03*
Y405985D03*
Y395985D03*
Y375985D03*
X800065D03*
X790065Y365985D03*
X800065D03*
Y355985D03*
X790065D03*
X809702Y416359D03*
X815600Y386200D03*
X800065Y455985D03*
Y465985D03*
X790065D03*
Y455985D03*
Y445985D03*
Y435985D03*
X790191Y426486D03*
X805771Y518743D03*
X789604Y519082D03*
X794604D03*
X825000Y536200D03*
X817519Y536435D03*
X811614D03*
X805708D03*
X841141D03*
X837204D03*
X799803D03*
X793897D03*
X787992D03*
X790975Y621407D03*
X795975D03*
X800975D03*
X805975D03*
X810975D03*
X815975D03*
X820975D03*
X825975D03*
X830975D03*
X835975D03*
X840975D03*
X854971Y637313D03*
Y642313D03*
Y647313D03*
Y652313D03*
Y657313D03*
Y662313D03*
Y667313D03*
Y672313D03*
Y677313D03*
Y682313D03*
Y687313D03*
Y692313D03*
Y697313D03*
Y702313D03*
Y707313D03*
Y712313D03*
X916683Y62377D03*
Y57377D03*
Y52377D03*
Y47377D03*
Y42377D03*
Y37377D03*
Y32377D03*
Y27377D03*
Y22377D03*
Y17377D03*
X915546Y8514D03*
X910546D03*
X905546D03*
X900546D03*
X916683Y132377D03*
Y127377D03*
Y122377D03*
Y117377D03*
Y112377D03*
Y107377D03*
Y102377D03*
Y97377D03*
Y92377D03*
Y87377D03*
Y82377D03*
Y77377D03*
Y72377D03*
Y67377D03*
Y207377D03*
Y202377D03*
Y197377D03*
Y192377D03*
Y187377D03*
Y182377D03*
Y177377D03*
Y172377D03*
Y167377D03*
Y162377D03*
Y157377D03*
Y152377D03*
Y147377D03*
Y142377D03*
Y137377D03*
Y277377D03*
Y272377D03*
Y267377D03*
Y262377D03*
Y257377D03*
Y252377D03*
Y247377D03*
Y242377D03*
Y237377D03*
Y232377D03*
Y227377D03*
Y222377D03*
Y217377D03*
Y212377D03*
X897195Y275688D03*
X902195D03*
Y270688D03*
X897195D03*
X916683Y347377D03*
Y342377D03*
Y337377D03*
Y332377D03*
Y327377D03*
Y322377D03*
Y317377D03*
Y312377D03*
Y307377D03*
Y302377D03*
Y297377D03*
Y292377D03*
Y287377D03*
Y282377D03*
X896030Y296330D03*
X901030D03*
X900995Y290712D03*
X895995D03*
X900819Y316367D03*
X895819D03*
X900716Y311058D03*
X895716D03*
X916683Y422377D03*
Y417377D03*
Y412377D03*
Y407377D03*
Y402377D03*
Y397377D03*
Y392377D03*
Y387377D03*
Y382377D03*
Y377377D03*
Y372377D03*
Y367377D03*
Y362377D03*
Y357377D03*
Y352377D03*
Y492377D03*
Y487377D03*
Y482377D03*
Y477377D03*
Y472377D03*
Y467377D03*
Y462377D03*
Y457377D03*
Y452377D03*
Y447377D03*
Y442377D03*
Y437377D03*
Y432377D03*
Y427377D03*
Y562377D03*
Y557377D03*
Y552377D03*
Y547377D03*
Y542377D03*
Y537377D03*
Y532377D03*
Y527377D03*
Y522377D03*
Y517377D03*
Y512377D03*
Y507377D03*
Y502377D03*
Y497377D03*
Y637377D03*
Y632377D03*
Y627377D03*
Y622377D03*
Y617377D03*
Y612377D03*
Y607377D03*
Y602377D03*
Y597377D03*
Y592377D03*
Y587377D03*
Y582377D03*
Y577377D03*
Y572377D03*
Y567377D03*
Y707377D03*
Y702377D03*
Y697377D03*
Y692377D03*
Y687377D03*
Y682377D03*
Y677377D03*
Y672377D03*
Y667377D03*
Y662377D03*
Y657377D03*
Y652377D03*
Y647377D03*
Y642377D03*
X901041Y753684D03*
X903277Y749212D03*
X905513Y744740D03*
X907749Y740268D03*
X909985Y735796D03*
X912221Y731323D03*
X914457Y726851D03*
X916683Y722377D03*
Y717377D03*
Y712377D03*
G54D36*
X706299Y83661D03*
Y201771D03*
X804724Y83661D03*
Y201772D03*
G54D35*
X488838Y164744D03*
G54D14*
X34652Y111485D03*
X33297Y703990D03*
X148206Y21054D03*
X261147Y405580D03*
X486498Y356293D03*
X807831Y734367D03*
X899219Y47960D03*
G54D34*
X488838Y137225D03*
G54D20*
X89764Y238386D03*
X309252Y413583D03*
G54D25*
X163189Y669291D03*
G54D30*
X339331Y91929D03*
X360669Y49803D03*
G54D21*
X90157Y413582D03*
X309055Y157677D03*
G54D15*
X70865Y98425D03*
Y472441D03*
X314960D03*
X364173Y740157D03*
X405511Y39370D03*
X587795Y307087D03*
X590551Y472441D03*
X612204Y606299D03*
X875984Y472441D03*
Y606299D03*
Y740157D03*
G54D19*
X49212D03*
X875984Y31496D03*
G54D16*
X67853Y558117D03*
X64277Y502177D03*
X106272Y547370D03*
X89899Y558115D03*
X69904Y502077D03*
X75399Y502179D03*
X81094Y502166D03*
X86699Y502300D03*
X97926D03*
X108371Y577258D03*
X86750Y567565D03*
X93048Y577014D03*
X86750Y573864D03*
X89899D03*
X75197Y572437D03*
X194094Y539370D03*
X203542Y545671D03*
X197243Y539371D03*
X194093Y564569D03*
X190944D03*
X194093Y555120D03*
X184646D03*
X153149Y536221D03*
X165748Y558268D03*
X172048Y555120D03*
X187925Y564617D03*
X168898Y561417D03*
X206692Y555120D03*
X175196Y589764D03*
X194093Y574016D03*
Y567718D03*
X190944Y574016D03*
Y567718D03*
X172048Y589764D03*
X168898D03*
X187844Y574065D03*
X184645Y574166D03*
X187746Y567669D03*
X184695Y567666D03*
X184646Y570867D03*
X168898Y570866D03*
X156299Y586614D03*
Y580315D03*
X159449Y567717D03*
X156299Y570866D03*
X200393Y589764D03*
X187900Y589800D03*
X187794Y586614D03*
X203542Y589764D03*
X200393Y596063D03*
X203605Y605821D03*
X153149Y605513D03*
X206692Y592913D03*
X165748Y583464D03*
X209842D03*
X212992Y586614D03*
X148249Y695765D03*
X222440Y605512D03*
X225900Y615000D03*
X353700Y670900D03*
X668847Y27107D03*
X663847D03*
X658847D03*
X653847D03*
X716100Y442100D03*
X721100D03*
X850730Y350483D03*
X841116Y348914D03*
X820059Y331701D03*
X857020Y383172D03*
Y379572D03*
Y386772D03*
X815541Y354089D03*
X847720Y371072D03*
X804000Y441100D03*
X799000D03*
X883222Y59214D03*
X888022D03*
X892822D03*
X897622D03*
X880922Y63714D03*
X885722D03*
X890522D03*
X895322D03*
X900122D03*
X875272Y186265D03*
X878872D03*
X860872D03*
X871672D03*
X868072D03*
X864472D03*
X878372Y191265D03*
X878872Y196265D03*
X864472D03*
X868072D03*
X871672D03*
X875272D03*
X865372Y191265D03*
X873872D03*
X869622D03*
X860872Y196265D03*
Y191265D03*
X871420Y383172D03*
X875020D03*
Y379572D03*
X871420D03*
X867820D03*
X860620D03*
X864220D03*
X875020Y386772D03*
X871420D03*
X867820D03*
X860620D03*
X864220D03*
X867820Y383172D03*
X860620D03*
X864220D03*
G54D17*
X28782Y555119D03*
X34132Y521245D03*
X34175Y526969D03*
X29165Y532612D03*
X29058Y538228D03*
X29158Y543855D03*
X28800Y549474D03*
X33697Y560866D03*
X67852Y583313D03*
Y586463D03*
X118197Y490300D03*
X71002Y577013D03*
X186254Y463761D03*
X179000Y499800D03*
X184645Y539370D03*
X184646Y577166D03*
X187795Y592914D03*
Y602363D03*
X304800Y554443D03*
X304124Y570227D03*
X334923Y579949D03*
X421653Y126378D03*
X428740Y121654D03*
Y135827D03*
X421653Y183071D03*
Y140551D03*
Y154725D03*
X428740Y150000D03*
X421653Y168898D03*
X428740Y164173D03*
X435827Y126378D03*
X450000D03*
X464173D03*
X442913Y121654D03*
X457086D03*
X471260D03*
X442913Y135827D03*
X457086D03*
X471260D03*
X435827Y183071D03*
X450000D03*
X464173D03*
X435827Y140551D03*
X450000D03*
X464173D03*
X435827Y154725D03*
X442913Y150000D03*
X450000Y154725D03*
X457086Y150000D03*
X464173Y154725D03*
X471260Y150000D03*
X435827Y168898D03*
X442913Y164173D03*
X450000Y168898D03*
X457086Y164173D03*
X464173Y168898D03*
X471260Y164173D03*
X506693Y126378D03*
X520866D03*
X535039D03*
X549212D03*
X513779Y121654D03*
X527953D03*
X542126D03*
X556299D03*
X513779Y135827D03*
X527953D03*
X542126D03*
X556299D03*
X506693Y183071D03*
X520866D03*
X535039D03*
X549212D03*
X506693Y140551D03*
X520866D03*
X535039D03*
X549212D03*
X506693Y154725D03*
X513779Y150000D03*
X520866Y154725D03*
X527953Y150000D03*
X535039Y154725D03*
X542126Y150000D03*
X549212Y154725D03*
X556299Y150000D03*
X506693Y168898D03*
X513779Y164173D03*
X520866Y168898D03*
X527953Y164173D03*
X535039Y168898D03*
X542126Y164173D03*
X549212Y168898D03*
X556299Y164173D03*
X576649Y39585D03*
X575300Y45967D03*
X725288Y405950D03*
X740500Y426800D03*
X716536Y523519D03*
X728036D03*
X854596Y155288D03*
X840122Y156614D03*
X843160Y169467D03*
X858632Y216929D03*
X808188Y404950D03*
X856720Y409372D03*
X822300Y418900D03*
X897803Y207684D03*
X902803D03*
X897803Y217684D03*
Y212684D03*
X902803Y217684D03*
Y212684D03*
X876451Y407949D03*
X880665Y410841D03*
X885665D03*
X890665D03*
X895665D03*
X900665D03*
G54D38*
X715000Y547027D03*
X705853Y549017D03*
X713985Y557149D03*
X696624Y548249D03*
X704756Y556381D03*
X683369Y549269D03*
X691501Y557401D03*
X681989Y540183D03*
X690121Y548315D03*
X668195Y541742D03*
X676327Y549874D03*
X655092Y536171D03*
X663224Y544303D03*
X785434Y551934D03*
X775934Y550934D03*
X784066Y559066D03*
X765434Y549934D03*
X773566Y558066D03*
X753434Y545434D03*
X761566Y553566D03*
X725853Y547117D03*
X733985Y555249D03*
X723132Y555159D03*
X822434Y550434D03*
X830566Y558566D03*
X809934Y545434D03*
X818066Y553566D03*
X803934Y551934D03*
X812066Y560066D03*
X794934Y551434D03*
X803066Y559566D03*
X793566Y560066D03*
G54D41*
X811024Y24409D03*
G54D27*
X346457Y57007D03*
%LPC*%
G75*
G54D43*
G01X-36569Y-23804D02*
Y-103804D01*
G01D02*
X1258031D01*
G01X-40569Y-7804D02*
G02I-12000J0D01*
G01X-45719D02*
G02I-6850J0D01*
G01X-52569Y-23804D02*
Y8196D01*
G01X-36569Y-23804D02*
X1258031D01*
G01X-36569Y-59304D02*
X1258031D01*
G01X-36569Y-7804D02*
X-68569D01*
G01X470531Y-23804D02*
Y-103804D01*
G01X608031Y-23804D02*
Y-103804D01*
G01X723031Y-23804D02*
Y-103804D01*
G01X890531Y-23804D02*
Y-103804D01*
G01X1060531Y-23804D02*
Y-103804D01*
G01X1258031Y-23804D02*
Y-103804D01*
G01X1286031Y-7804D02*
G02I-12000J0D01*
G01X1280881D02*
G02I-6850J0D01*
G01X1274031Y-23804D02*
Y8196D01*
G01X1290031Y-7804D02*
X1258031D01*
G54D44*
G01X-9023Y-84471D02*
X-8149Y-83596D01*
X-7494Y-82138D01*
X-7057Y-80095D01*
X-7494Y-78346D01*
X-8367Y-77179D01*
X-9896Y-76304D01*
X-15791D01*
Y-93804D01*
X-8586D01*
X-7057Y-92638D01*
X-6184Y-90887D01*
X-5747Y-88846D01*
X-6184Y-86804D01*
X-7494Y-85054D01*
X-9023Y-84471D01*
X-15791D01*
G01X3674Y-93804D02*
Y-82138D01*
G01Y-84471D02*
X4766Y-83304D01*
X5858Y-82429D01*
X7386Y-82138D01*
X8477Y-82429D01*
X9788Y-83304D01*
G01X19646Y-99054D02*
X20956Y-99637D01*
X22703Y-99054D01*
X23794Y-97888D01*
X24668Y-96429D01*
X25977Y-91763D01*
X28816Y-82138D01*
G01X21829D02*
X25977Y-91763D01*
G01X45224Y-83596D02*
X43696Y-82429D01*
X42386Y-82138D01*
X40639Y-82721D01*
X39329Y-83887D01*
X38456Y-85929D01*
X38237Y-87971D01*
X38456Y-90013D01*
X39329Y-91763D01*
X40639Y-93221D01*
X42386Y-93804D01*
X43914Y-93221D01*
X45224Y-92054D01*
G01X55956Y-85929D02*
X62943D01*
X62288Y-83887D01*
X61196Y-82721D01*
X59668Y-82138D01*
X58139Y-82429D01*
X56829Y-83304D01*
X55956Y-85346D01*
X55519Y-87096D01*
Y-88846D01*
X55956Y-90596D01*
X57048Y-92346D01*
X58358Y-93512D01*
X59886Y-93804D01*
X61414Y-93221D01*
X62943Y-91471D01*
G01X99034Y-77763D02*
X97724Y-76887D01*
X96196Y-76304D01*
X94449D01*
X92484Y-77179D01*
X90956Y-78637D01*
X89864Y-80388D01*
X88991Y-83304D01*
X88772Y-85929D01*
X89209Y-88554D01*
X89864Y-90304D01*
X91174Y-92054D01*
X92703Y-93221D01*
X94231Y-93804D01*
X95759D01*
X97288Y-93221D01*
X98598Y-92346D01*
X99690Y-91180D01*
G01X115661Y-93804D02*
Y-82138D01*
G01Y-84179D02*
X114788Y-83013D01*
X113477Y-82429D01*
X111949Y-82138D01*
X110421Y-82721D01*
X109111Y-83887D01*
X108237Y-85637D01*
X107801Y-87971D01*
X108237Y-90304D01*
X109111Y-92054D01*
X110421Y-93221D01*
X111949Y-93804D01*
X113477Y-93512D01*
X114788Y-92638D01*
X115661Y-91471D01*
G01X125519Y-93804D02*
Y-82138D01*
G01Y-85054D02*
X126393Y-83596D01*
X127703Y-82429D01*
X129449Y-82138D01*
X130977Y-82429D01*
X132288Y-83596D01*
X132943Y-85637D01*
Y-93804D01*
G01X142146Y-99054D02*
X143456Y-99637D01*
X145203Y-99054D01*
X146294Y-97888D01*
X147168Y-96429D01*
X148477Y-91763D01*
X151316Y-82138D01*
G01X144329D02*
X148477Y-91763D01*
G01X164231Y-93804D02*
X162921Y-93512D01*
X161611Y-92346D01*
X160737Y-90304D01*
X160301Y-87971D01*
X160737Y-85637D01*
X161611Y-83596D01*
X162921Y-82429D01*
X164231Y-82138D01*
X165541Y-82429D01*
X166851Y-83596D01*
X167724Y-85637D01*
X167943Y-87971D01*
X167724Y-90304D01*
X166851Y-92346D01*
X165541Y-93512D01*
X164231Y-93804D01*
G01X178019D02*
Y-82138D01*
G01Y-85054D02*
X178893Y-83596D01*
X180203Y-82429D01*
X181949Y-82138D01*
X183477Y-82429D01*
X184788Y-83596D01*
X185443Y-85637D01*
Y-93804D01*
G01X214111Y-76304D02*
X219351D01*
G01X216731D02*
Y-93804D01*
G01X214111D02*
X219351D01*
G01X234231D02*
X232484Y-93512D01*
X230956Y-92346D01*
X229646Y-90596D01*
X228772Y-88554D01*
X228336Y-86221D01*
Y-83887D01*
X228772Y-81554D01*
X229646Y-79512D01*
X230956Y-77763D01*
X232484Y-76596D01*
X234231Y-76304D01*
X235977Y-76596D01*
X237506Y-77763D01*
X238816Y-79512D01*
X239690Y-81554D01*
X240126Y-83887D01*
Y-86221D01*
X239690Y-88554D01*
X238816Y-90596D01*
X237506Y-92346D01*
X235977Y-93512D01*
X234231Y-93804D01*
G01X246054D02*
Y-76304D01*
X251731Y-90887D01*
X257408Y-76304D01*
Y-93804D01*
G01X285639Y-99637D02*
X283456Y-96721D01*
X282364Y-93804D01*
Y-82138D01*
X283456Y-79221D01*
X285639Y-76304D01*
G01X298554Y-93804D02*
Y-76304D01*
X304231Y-90887D01*
X309908Y-76304D01*
Y-93804D01*
G01X321731Y-94387D02*
X321294Y-94096D01*
Y-93512D01*
X321731Y-93221D01*
X322168Y-93512D01*
Y-94096D01*
X321731Y-94387D01*
G01X335083Y-79221D02*
X336393Y-77471D01*
X337921Y-76596D01*
X339668Y-76304D01*
X341851Y-76887D01*
X343379Y-78346D01*
X343816Y-80095D01*
X343598Y-81846D01*
X342724Y-83304D01*
X338358Y-86221D01*
X336393Y-88262D01*
X335083Y-91180D01*
X334646Y-93804D01*
X343816D01*
G01X374231D02*
X372921Y-93512D01*
X371611Y-92346D01*
X370737Y-90304D01*
X370301Y-87971D01*
X370737Y-85637D01*
X371611Y-83596D01*
X372921Y-82429D01*
X374231Y-82138D01*
X375541Y-82429D01*
X376851Y-83596D01*
X377724Y-85637D01*
X377943Y-87971D01*
X377724Y-90304D01*
X376851Y-92346D01*
X375541Y-93512D01*
X374231Y-93804D01*
G01X388019D02*
Y-82138D01*
G01Y-85054D02*
X388893Y-83596D01*
X390203Y-82429D01*
X391949Y-82138D01*
X393477Y-82429D01*
X394788Y-83596D01*
X395443Y-85637D01*
Y-93804D01*
G01X409231D02*
Y-76304D01*
G01X422146Y-99054D02*
X423456Y-99637D01*
X425203Y-99054D01*
X426294Y-97888D01*
X427168Y-96429D01*
X428477Y-91763D01*
X431316Y-82138D01*
G01X424329D02*
X428477Y-91763D01*
G01X445323Y-99637D02*
X447506Y-96721D01*
X448598Y-93804D01*
Y-82138D01*
X447506Y-79221D01*
X445323Y-76304D01*
G01X176054Y-48804D02*
Y-31304D01*
X181731Y-45887D01*
X187408Y-31304D01*
Y-48804D01*
G01X199231D02*
X197921Y-48512D01*
X196611Y-47346D01*
X195737Y-45304D01*
X195301Y-42971D01*
X195737Y-40637D01*
X196611Y-38596D01*
X197921Y-37429D01*
X199231Y-37138D01*
X200541Y-37429D01*
X201851Y-38596D01*
X202724Y-40637D01*
X202943Y-42971D01*
X202724Y-45304D01*
X201851Y-47346D01*
X200541Y-48512D01*
X199231Y-48804D01*
G01X220661Y-31304D02*
Y-48804D01*
G01Y-46180D02*
X219788Y-47638D01*
X218477Y-48512D01*
X216949Y-48804D01*
X215203Y-48221D01*
X213893Y-46763D01*
X213019Y-45013D01*
X212801Y-42971D01*
X213019Y-40929D01*
X213893Y-39179D01*
X215203Y-37721D01*
X216949Y-37138D01*
X218477Y-37429D01*
X219569Y-38013D01*
X220661Y-39179D01*
G01X230956Y-40929D02*
X237943D01*
X237288Y-38887D01*
X236196Y-37721D01*
X234668Y-37138D01*
X233139Y-37429D01*
X231829Y-38304D01*
X230956Y-40346D01*
X230519Y-42096D01*
Y-43846D01*
X230956Y-45596D01*
X232048Y-47346D01*
X233358Y-48512D01*
X234886Y-48804D01*
X236414Y-48221D01*
X237943Y-46471D01*
G01X251731Y-48804D02*
Y-31304D01*
G01X504231Y-93804D02*
Y-76304D01*
X501611Y-79804D01*
G01Y-93804D02*
X506851D01*
G01X517583Y-86513D02*
X519111Y-84471D01*
X520421Y-83304D01*
X522168Y-82721D01*
X523696Y-83304D01*
X524788Y-84471D01*
X525661Y-86221D01*
X525879Y-88262D01*
X525661Y-90013D01*
X524788Y-91763D01*
X523477Y-93221D01*
X521949Y-93804D01*
X520203Y-93221D01*
X518674Y-91471D01*
X517801Y-88846D01*
X517583Y-85929D01*
X518019Y-82138D01*
X518674Y-80095D01*
X519766Y-78054D01*
X521294Y-76596D01*
X522823Y-76304D01*
X524351Y-76887D01*
X525443Y-78346D01*
G01X534428Y-90304D02*
X535737Y-92346D01*
X537484Y-93512D01*
X539449Y-93804D01*
X541196Y-93512D01*
X542943Y-92054D01*
X544034Y-90304D01*
X544253Y-88554D01*
X543816Y-86513D01*
X542288Y-85054D01*
X540759Y-84471D01*
X538794D01*
G01X540759D02*
X542069Y-83596D01*
X543161Y-82138D01*
X543598Y-80388D01*
X543161Y-78637D01*
X542069Y-77179D01*
X540104Y-76304D01*
X538139Y-76596D01*
X536174Y-77763D01*
G01X559351Y-93804D02*
Y-76304D01*
X551272Y-88846D01*
X562190D01*
G01X570083Y-79221D02*
X571393Y-77471D01*
X572921Y-76596D01*
X574668Y-76304D01*
X576851Y-76887D01*
X578379Y-78346D01*
X578816Y-80095D01*
X578598Y-81846D01*
X577724Y-83304D01*
X573358Y-86221D01*
X571393Y-88262D01*
X570083Y-91180D01*
X569646Y-93804D01*
X578816D01*
G01X491114Y-48804D02*
Y-31304D01*
X496354D01*
X498101Y-32179D01*
X499411Y-34221D01*
X499848Y-36554D01*
X499411Y-38887D01*
X498319Y-40637D01*
X496354Y-41513D01*
X491114D01*
G01X517784Y-32763D02*
X516474Y-31887D01*
X514946Y-31304D01*
X513199D01*
X511234Y-32179D01*
X509706Y-33637D01*
X508614Y-35388D01*
X507741Y-38304D01*
X507522Y-40929D01*
X507959Y-43554D01*
X508614Y-45304D01*
X509924Y-47054D01*
X511453Y-48221D01*
X512981Y-48804D01*
X514509D01*
X516038Y-48221D01*
X517348Y-47346D01*
X518440Y-46180D01*
G01X532227Y-39471D02*
X533101Y-38596D01*
X533756Y-37138D01*
X534193Y-35095D01*
X533756Y-33346D01*
X532883Y-32179D01*
X531354Y-31304D01*
X525459D01*
Y-48804D01*
X532664D01*
X534193Y-47638D01*
X535066Y-45887D01*
X535503Y-43846D01*
X535066Y-41804D01*
X533756Y-40054D01*
X532227Y-39471D01*
X525459D01*
G01X541431Y-54637D02*
X554531D01*
G01X560459Y-48804D02*
Y-31304D01*
X570503Y-48804D01*
Y-31304D01*
G01X582981Y-48804D02*
X581234Y-48512D01*
X579706Y-47346D01*
X578396Y-45596D01*
X577522Y-43554D01*
X577086Y-41221D01*
Y-38887D01*
X577522Y-36554D01*
X578396Y-34512D01*
X579706Y-32763D01*
X581234Y-31596D01*
X582981Y-31304D01*
X584727Y-31596D01*
X586256Y-32763D01*
X587566Y-34512D01*
X588440Y-36554D01*
X588876Y-38887D01*
Y-41221D01*
X588440Y-43554D01*
X587566Y-45596D01*
X586256Y-47346D01*
X584727Y-48512D01*
X582981Y-48804D01*
G01X633822Y-31304D02*
X639281Y-48804D01*
X644740Y-31304D01*
G01X661148Y-48804D02*
X652414D01*
Y-31304D01*
X661148D01*
G01X657654Y-39762D02*
X652414D01*
G01X669914Y-48804D02*
Y-31304D01*
X675373D01*
X677119Y-32179D01*
X678211Y-33346D01*
X678648Y-35679D01*
X678211Y-38013D01*
X676901Y-39471D01*
X675373Y-40346D01*
X669914D01*
G01X675373D02*
X678648Y-48804D01*
G01X691781Y-49387D02*
X691344Y-49096D01*
Y-48512D01*
X691781Y-48221D01*
X692218Y-48512D01*
Y-49096D01*
X691781Y-49387D01*
G01X661383Y-79221D02*
X662693Y-77471D01*
X664221Y-76596D01*
X665968Y-76304D01*
X668151Y-76887D01*
X669679Y-78346D01*
X670116Y-80095D01*
X669898Y-81846D01*
X669024Y-83304D01*
X664658Y-86221D01*
X662693Y-88262D01*
X661383Y-91180D01*
X660946Y-93804D01*
X670116D01*
G01X846098Y-76304D02*
Y-93804D01*
X837364D01*
G01X824668D02*
X824231Y-90013D01*
X823576Y-86804D01*
X822703Y-83887D01*
X821611Y-80679D01*
X819864Y-76304D01*
X828598D01*
G01X805421Y-85054D02*
X801054D01*
Y-90304D01*
X802364Y-92054D01*
X803893Y-93221D01*
X806076Y-93804D01*
X808259Y-93221D01*
X809788Y-92054D01*
X811098Y-90304D01*
X811971Y-88262D01*
X812408Y-85929D01*
Y-83887D01*
X811971Y-82138D01*
X811098Y-80095D01*
X809788Y-78346D01*
X808478Y-77179D01*
X806731Y-76304D01*
X805203D01*
X803456Y-76887D01*
X802146Y-78054D01*
G01X794253Y-93804D02*
Y-76304D01*
X784209Y-93804D01*
Y-76304D01*
G01X776534Y-93804D02*
Y-76304D01*
X772168D01*
X770421Y-77179D01*
X769111Y-78346D01*
X768019Y-80095D01*
X767146Y-82138D01*
X766928Y-85054D01*
X767146Y-87971D01*
X768019Y-90013D01*
X769111Y-91763D01*
X770421Y-92929D01*
X772168Y-93804D01*
X776534D01*
G01X767364Y-31304D02*
Y-48804D01*
X776098D01*
G01X793161D02*
Y-37138D01*
G01Y-39179D02*
X792288Y-38013D01*
X790977Y-37429D01*
X789449Y-37138D01*
X787921Y-37721D01*
X786611Y-38887D01*
X785737Y-40637D01*
X785301Y-42971D01*
X785737Y-45304D01*
X786611Y-47054D01*
X787921Y-48221D01*
X789449Y-48804D01*
X790977Y-48512D01*
X792288Y-47638D01*
X793161Y-46471D01*
G01X802146Y-54054D02*
X803456Y-54637D01*
X805203Y-54054D01*
X806294Y-52888D01*
X807168Y-51429D01*
X808477Y-46763D01*
X811316Y-37138D01*
G01X804329D02*
X808477Y-46763D01*
G01X820956Y-40929D02*
X827943D01*
X827288Y-38887D01*
X826196Y-37721D01*
X824668Y-37138D01*
X823139Y-37429D01*
X821829Y-38304D01*
X820956Y-40346D01*
X820519Y-42096D01*
Y-43846D01*
X820956Y-45596D01*
X822048Y-47346D01*
X823358Y-48512D01*
X824886Y-48804D01*
X826414Y-48221D01*
X827943Y-46471D01*
G01X838674Y-48804D02*
Y-37138D01*
G01Y-39471D02*
X839766Y-38304D01*
X840858Y-37429D01*
X842386Y-37138D01*
X843477Y-37429D01*
X844788Y-38304D01*
G01X931781Y-93804D02*
X930034Y-93512D01*
X928506Y-92346D01*
X927196Y-90596D01*
X926322Y-88554D01*
X925886Y-86221D01*
Y-83887D01*
X926322Y-81554D01*
X927196Y-79512D01*
X928506Y-77763D01*
X930034Y-76596D01*
X931781Y-76304D01*
X933527Y-76596D01*
X935056Y-77763D01*
X936366Y-79512D01*
X937240Y-81554D01*
X937676Y-83887D01*
Y-86221D01*
X937240Y-88554D01*
X936366Y-90596D01*
X935056Y-92346D01*
X933527Y-93512D01*
X931781Y-93804D01*
G01X933527Y-89137D02*
X936148Y-93804D01*
G01X944478Y-76304D02*
Y-88846D01*
X945351Y-91471D01*
X947098Y-93221D01*
X949281Y-93804D01*
X951464Y-93221D01*
X953211Y-91471D01*
X954084Y-88846D01*
Y-76304D01*
G01X964161D02*
X969401D01*
G01X966781D02*
Y-93804D01*
G01X964161D02*
X969401D01*
G01X979259D02*
Y-76304D01*
X989303Y-93804D01*
Y-76304D01*
G01X1006584Y-77763D02*
X1005274Y-76887D01*
X1003746Y-76304D01*
X1001999D01*
X1000034Y-77179D01*
X998506Y-78637D01*
X997414Y-80388D01*
X996541Y-83304D01*
X996322Y-85929D01*
X996759Y-88554D01*
X997414Y-90304D01*
X998724Y-92054D01*
X1000253Y-93221D01*
X1001781Y-93804D01*
X1003309D01*
X1004838Y-93221D01*
X1006148Y-92346D01*
X1007240Y-91180D01*
G01X1019281Y-93804D02*
Y-85929D01*
X1014914Y-76304D01*
G01X1023648D02*
X1019281Y-85929D01*
G01X909478Y-48804D02*
Y-31304D01*
X913844D01*
X915591Y-32179D01*
X916901Y-33346D01*
X917993Y-35095D01*
X918866Y-37138D01*
X919084Y-40054D01*
X918866Y-42971D01*
X917993Y-45013D01*
X916901Y-46763D01*
X915591Y-47929D01*
X913844Y-48804D01*
X909478D01*
G01X928506Y-40929D02*
X935493D01*
X934838Y-38887D01*
X933746Y-37721D01*
X932218Y-37138D01*
X930689Y-37429D01*
X929379Y-38304D01*
X928506Y-40346D01*
X928069Y-42096D01*
Y-43846D01*
X928506Y-45596D01*
X929598Y-47346D01*
X930908Y-48512D01*
X932436Y-48804D01*
X933964Y-48221D01*
X935493Y-46471D01*
G01X946006Y-46763D02*
X947098Y-47929D01*
X948626Y-48804D01*
X949936D01*
X951246Y-48221D01*
X952119Y-47346D01*
X952556Y-46180D01*
X952338Y-44429D01*
X951464Y-43554D01*
X947534Y-41804D01*
X946661Y-39762D01*
X947098Y-38304D01*
X947971Y-37429D01*
X949281Y-37138D01*
X950591Y-37429D01*
X951901Y-38304D01*
G01X966781Y-37138D02*
Y-48804D01*
G01Y-32471D02*
X966344Y-32179D01*
Y-31596D01*
X966781Y-31304D01*
X967218Y-31596D01*
Y-32179D01*
X966781Y-32471D01*
G01X981224Y-53179D02*
X982753Y-54346D01*
X984499Y-54637D01*
X986027Y-54346D01*
X987338Y-52888D01*
X988211Y-50846D01*
Y-37138D01*
G01Y-39471D02*
X987338Y-38304D01*
X986027Y-37429D01*
X984499Y-37138D01*
X982753Y-37721D01*
X981661Y-38887D01*
X980787Y-40929D01*
X980351Y-42971D01*
X980569Y-44721D01*
X981443Y-46763D01*
X982753Y-48221D01*
X984499Y-48804D01*
X985809Y-48512D01*
X987338Y-47346D01*
X988211Y-46180D01*
G01X998069Y-48804D02*
Y-37138D01*
G01Y-40054D02*
X998943Y-38596D01*
X1000253Y-37429D01*
X1001999Y-37138D01*
X1003527Y-37429D01*
X1004838Y-38596D01*
X1005493Y-40637D01*
Y-48804D01*
G01X1016006Y-40929D02*
X1022993D01*
X1022338Y-38887D01*
X1021246Y-37721D01*
X1019718Y-37138D01*
X1018189Y-37429D01*
X1016879Y-38304D01*
X1016006Y-40346D01*
X1015569Y-42096D01*
Y-43846D01*
X1016006Y-45596D01*
X1017098Y-47346D01*
X1018408Y-48512D01*
X1019936Y-48804D01*
X1021464Y-48221D01*
X1022993Y-46471D01*
G01X1033724Y-48804D02*
Y-37138D01*
G01Y-39471D02*
X1034816Y-38304D01*
X1035908Y-37429D01*
X1037436Y-37138D01*
X1038527Y-37429D01*
X1039838Y-38304D01*
G01X1080481Y-76304D02*
X1078734Y-76887D01*
X1077424Y-78346D01*
X1076551Y-80095D01*
X1075896Y-82429D01*
X1075678Y-85054D01*
X1075896Y-87679D01*
X1076551Y-90013D01*
X1077424Y-91763D01*
X1078734Y-93221D01*
X1080481Y-93804D01*
X1082227Y-93221D01*
X1083538Y-91763D01*
X1084411Y-90013D01*
X1085066Y-87679D01*
X1085284Y-85054D01*
X1085066Y-82429D01*
X1084411Y-80095D01*
X1083538Y-78346D01*
X1082227Y-76887D01*
X1080481Y-76304D01*
G01X1097981Y-93804D02*
X1099509Y-93512D01*
X1101256Y-92638D01*
X1102348Y-91180D01*
X1102784Y-89137D01*
X1102348Y-87096D01*
X1101038Y-85346D01*
X1099073Y-84471D01*
X1096889D01*
X1095579Y-83887D01*
X1094487Y-82429D01*
X1094051Y-80388D01*
X1094706Y-78346D01*
X1096234Y-76887D01*
X1097981Y-76304D01*
X1099727Y-76887D01*
X1101256Y-78346D01*
X1101911Y-80388D01*
X1101474Y-82429D01*
X1100383Y-83887D01*
X1099073Y-84471D01*
X1096889D01*
X1094924Y-85346D01*
X1093614Y-87096D01*
X1093178Y-89137D01*
X1093614Y-91180D01*
X1094706Y-92638D01*
X1096453Y-93512D01*
X1097981Y-93804D01*
G01X1111551Y-94387D02*
X1119411Y-76304D01*
G01X1132981D02*
X1131234Y-76887D01*
X1129924Y-78346D01*
X1129051Y-80095D01*
X1128396Y-82429D01*
X1128178Y-85054D01*
X1128396Y-87679D01*
X1129051Y-90013D01*
X1129924Y-91763D01*
X1131234Y-93221D01*
X1132981Y-93804D01*
X1134727Y-93221D01*
X1136038Y-91763D01*
X1136911Y-90013D01*
X1137566Y-87679D01*
X1137784Y-85054D01*
X1137566Y-82429D01*
X1136911Y-80095D01*
X1136038Y-78346D01*
X1134727Y-76887D01*
X1132981Y-76304D01*
G01X1150044Y-93804D02*
X1150481Y-90013D01*
X1151136Y-86804D01*
X1152009Y-83887D01*
X1153101Y-80679D01*
X1154848Y-76304D01*
X1146114D01*
G01X1164051Y-94387D02*
X1171911Y-76304D01*
G01X1181333Y-79221D02*
X1182643Y-77471D01*
X1184171Y-76596D01*
X1185918Y-76304D01*
X1188101Y-76887D01*
X1189629Y-78346D01*
X1190066Y-80095D01*
X1189848Y-81846D01*
X1188974Y-83304D01*
X1184608Y-86221D01*
X1182643Y-88262D01*
X1181333Y-91180D01*
X1180896Y-93804D01*
X1190066D01*
G01X1202981Y-76304D02*
X1201234Y-76887D01*
X1199924Y-78346D01*
X1199051Y-80095D01*
X1198396Y-82429D01*
X1198178Y-85054D01*
X1198396Y-87679D01*
X1199051Y-90013D01*
X1199924Y-91763D01*
X1201234Y-93221D01*
X1202981Y-93804D01*
X1204727Y-93221D01*
X1206038Y-91763D01*
X1206911Y-90013D01*
X1207566Y-87679D01*
X1207784Y-85054D01*
X1207566Y-82429D01*
X1206911Y-80095D01*
X1206038Y-78346D01*
X1204727Y-76887D01*
X1202981Y-76304D01*
G01X1220481Y-93804D02*
Y-76304D01*
X1217861Y-79804D01*
G01Y-93804D02*
X1223101D01*
G01X1237544D02*
X1237981Y-90013D01*
X1238636Y-86804D01*
X1239509Y-83887D01*
X1240601Y-80679D01*
X1242348Y-76304D01*
X1233614D01*
G01X1128178Y-48804D02*
Y-31304D01*
X1132544D01*
X1134291Y-32179D01*
X1135601Y-33346D01*
X1136693Y-35095D01*
X1137566Y-37138D01*
X1137784Y-40054D01*
X1137566Y-42971D01*
X1136693Y-45013D01*
X1135601Y-46763D01*
X1134291Y-47929D01*
X1132544Y-48804D01*
X1128178D01*
G01X1154411D02*
Y-37138D01*
G01Y-39179D02*
X1153538Y-38013D01*
X1152227Y-37429D01*
X1150699Y-37138D01*
X1149171Y-37721D01*
X1147861Y-38887D01*
X1146987Y-40637D01*
X1146551Y-42971D01*
X1146987Y-45304D01*
X1147861Y-47054D01*
X1149171Y-48221D01*
X1150699Y-48804D01*
X1152227Y-48512D01*
X1153538Y-47638D01*
X1154411Y-46471D01*
G01X1167981Y-31304D02*
Y-48804D01*
G01X1164924Y-37138D02*
X1171038D01*
G01X1182206Y-40929D02*
X1189193D01*
X1188538Y-38887D01*
X1187446Y-37721D01*
X1185918Y-37138D01*
X1184389Y-37429D01*
X1183079Y-38304D01*
X1182206Y-40346D01*
X1181769Y-42096D01*
Y-43846D01*
X1182206Y-45596D01*
X1183298Y-47346D01*
X1184608Y-48512D01*
X1186136Y-48804D01*
X1187664Y-48221D01*
X1189193Y-46471D01*
M02*
